FILE_TYPE = MACRO_DRAWING;
SET COLOR_WIRE YELLOW;
SET COLOR_PROP MONO;
SET COLOR_DOT WHITE;
SET COLOR_ARC YELLOW;
SET COLOR_BODY GREEN;
SET COLOR_NOTE MONO;
SET PROP_DISPLAY VALUE;
SET PAGE_NUMBER P83;
FORCEADD OFFPAGE..3
(1600 5250);
FORCEPROP 2 LAST $XR1 84 
J 0
(1904 5250);
DISPLAY 0.638298 (1904 5250);
PAINT MONO (1904 5250);
FORCEPROP 2 LAST $XR0 60 
J 0
(1814 5250);
DISPLAY 0.638298 (1814 5250);
PAINT MONO (1814 5250);
FORCEPROP 2 LAST CDS_LIB mstr_standard
J 0
(1600 5250);
DISPLAY 0.787234 (1600 5250);
PAINT MONO (1600 5250);
DISPLAY INVISIBLE (1600 5250);
FORCEPROP 1 LAST OFFPAGE TRUE
J 0
(1925 5125);
DISPLAY 0.936170 (1925 5125);
PAINT GREEN (1925 5125);
DISPLAY INVISIBLE (1925 5125);
FORCEPROP 1 LAST COMMENT_BODY TRUE
J 0
(1550 5150);
DISPLAY 0.936170 (1550 5150);
PAINT GREEN (1550 5150);
DISPLAY INVISIBLE (1550 5150);
FORCEPROP 2 LAST PATH I1
J 0
(1800 5325);
DISPLAY 0.787234 (1800 5325);
PAINT MONO (1800 5325);
DISPLAY INVISIBLE (1800 5325);
FORCEADD TAP..6
R 2
(700 4900);
FORCEPROP 3 LASTPIN (650 4900) SIG_NAME M_K_DQS_DP<14>
J 0
(660 4910);
DISPLAY 0.659574 (660 4910);
PAINT MONO (660 4910);
DISPLAY INVISIBLE (660 4910);
FORCEPROP 1 LASTPIN (650 4900) BN 14
J 2
(700 4910);
DISPLAY 0.617021 (700 4910);
PAINT PINK (700 4910);
FORCEPROP 2 LAST CDS_LIB mstr_standard
J 0
(700 4900);
DISPLAY 0.787234 (700 4900);
PAINT MONO (700 4900);
DISPLAY INVISIBLE (700 4900);
FORCEPROP 1 LAST BODY_TYPE PLUMBING
J 2
(700 4850);
DISPLAY 1.234043 (700 4850);
PAINT GREEN (700 4850);
DISPLAY INVISIBLE (700 4850);
FORCEPROP 1 LAST HDL_TAP TRUE
J 2
(375 4775);
DISPLAY 1.234043 (375 4775);
PAINT GREEN (375 4775);
DISPLAY INVISIBLE (375 4775);
FORCEPROP 1 LAST PATH I10
J 2
(700 4900);
DISPLAY 0.936170 (700 4900);
PAINT GREEN (700 4900);
DISPLAY INVISIBLE (700 4900);
FORCEADD TAP..6
R 2
(-1700 2150);
FORCEPROP 3 LASTPIN (-1750 2150) SIG_NAME M_K_DQ<8>
J 0
(-1740 2160);
DISPLAY 0.659574 (-1740 2160);
PAINT MONO (-1740 2160);
DISPLAY INVISIBLE (-1740 2160);
FORCEPROP 1 LASTPIN (-1750 2150) BN 8
J 2
(-1700 2160);
DISPLAY 0.617021 (-1700 2160);
PAINT PINK (-1700 2160);
FORCEPROP 2 LAST CDS_LIB mstr_standard
J 2
(-1700 2150);
DISPLAY 0.787234 (-1700 2150);
PAINT MONO (-1700 2150);
DISPLAY INVISIBLE (-1700 2150);
FORCEPROP 1 LAST BODY_TYPE PLUMBING
J 2
(-1700 2100);
DISPLAY 1.234043 (-1700 2100);
PAINT GREEN (-1700 2100);
DISPLAY INVISIBLE (-1700 2100);
FORCEPROP 1 LAST HDL_TAP TRUE
J 2
(-2025 2025);
DISPLAY 1.234043 (-2025 2025);
PAINT GREEN (-2025 2025);
DISPLAY INVISIBLE (-2025 2025);
FORCEPROP 1 LAST PATH I100
J 2
(-1700 2150);
DISPLAY 0.936170 (-1700 2150);
PAINT GREEN (-1700 2150);
DISPLAY INVISIBLE (-1700 2150);
FORCEADD TAP..6
R 2
(-1700 2200);
FORCEPROP 3 LASTPIN (-1750 2200) SIG_NAME M_K_DQ<11>
J 0
(-1740 2210);
DISPLAY 0.659574 (-1740 2210);
PAINT MONO (-1740 2210);
DISPLAY INVISIBLE (-1740 2210);
FORCEPROP 1 LASTPIN (-1750 2200) BN 11
J 2
(-1700 2210);
DISPLAY 0.617021 (-1700 2210);
PAINT PINK (-1700 2210);
FORCEPROP 2 LAST CDS_LIB mstr_standard
J 2
(-1700 2200);
DISPLAY 0.787234 (-1700 2200);
PAINT MONO (-1700 2200);
DISPLAY INVISIBLE (-1700 2200);
FORCEPROP 1 LAST BODY_TYPE PLUMBING
J 2
(-1700 2150);
DISPLAY 1.234043 (-1700 2150);
PAINT GREEN (-1700 2150);
DISPLAY INVISIBLE (-1700 2150);
FORCEPROP 1 LAST HDL_TAP TRUE
J 2
(-2025 2075);
DISPLAY 1.234043 (-2025 2075);
PAINT GREEN (-2025 2075);
DISPLAY INVISIBLE (-2025 2075);
FORCEPROP 1 LAST PATH I101
J 2
(-1700 2200);
DISPLAY 0.936170 (-1700 2200);
PAINT GREEN (-1700 2200);
DISPLAY INVISIBLE (-1700 2200);
FORCEADD TAP..6
R 2
(-1700 1900);
FORCEPROP 3 LASTPIN (-1750 1900) SIG_NAME M_K_DQ<5>
J 0
(-1740 1910);
DISPLAY 0.659574 (-1740 1910);
PAINT MONO (-1740 1910);
DISPLAY INVISIBLE (-1740 1910);
FORCEPROP 1 LASTPIN (-1750 1900) BN 5
J 2
(-1700 1910);
DISPLAY 0.617021 (-1700 1910);
PAINT PINK (-1700 1910);
FORCEPROP 2 LAST CDS_LIB mstr_standard
J 2
(-1700 1900);
DISPLAY 0.787234 (-1700 1900);
PAINT MONO (-1700 1900);
DISPLAY INVISIBLE (-1700 1900);
FORCEPROP 1 LAST BODY_TYPE PLUMBING
J 2
(-1700 1850);
DISPLAY 1.234043 (-1700 1850);
PAINT GREEN (-1700 1850);
DISPLAY INVISIBLE (-1700 1850);
FORCEPROP 1 LAST HDL_TAP TRUE
J 2
(-2025 1775);
DISPLAY 1.234043 (-2025 1775);
PAINT GREEN (-2025 1775);
DISPLAY INVISIBLE (-2025 1775);
FORCEPROP 1 LAST PATH I102
J 2
(-1700 1900);
DISPLAY 0.936170 (-1700 1900);
PAINT GREEN (-1700 1900);
DISPLAY INVISIBLE (-1700 1900);
FORCEADD TAP..6
R 2
(-1700 1850);
FORCEPROP 3 LASTPIN (-1750 1850) SIG_NAME M_K_DQ<2>
J 0
(-1740 1860);
DISPLAY 0.659574 (-1740 1860);
PAINT MONO (-1740 1860);
DISPLAY INVISIBLE (-1740 1860);
FORCEPROP 1 LASTPIN (-1750 1850) BN 2
J 2
(-1700 1860);
DISPLAY 0.617021 (-1700 1860);
PAINT PINK (-1700 1860);
FORCEPROP 2 LAST CDS_LIB mstr_standard
J 2
(-1700 1850);
DISPLAY 0.787234 (-1700 1850);
PAINT MONO (-1700 1850);
DISPLAY INVISIBLE (-1700 1850);
FORCEPROP 1 LAST BODY_TYPE PLUMBING
J 2
(-1700 1800);
DISPLAY 1.234043 (-1700 1800);
PAINT GREEN (-1700 1800);
DISPLAY INVISIBLE (-1700 1800);
FORCEPROP 1 LAST HDL_TAP TRUE
J 2
(-2025 1725);
DISPLAY 1.234043 (-2025 1725);
PAINT GREEN (-2025 1725);
DISPLAY INVISIBLE (-2025 1725);
FORCEPROP 1 LAST PATH I103
J 2
(-1700 1850);
DISPLAY 0.936170 (-1700 1850);
PAINT GREEN (-1700 1850);
DISPLAY INVISIBLE (-1700 1850);
FORCEADD TAP..6
R 2
(-1700 1950);
FORCEPROP 3 LASTPIN (-1750 1950) SIG_NAME M_K_DQ<4>
J 0
(-1740 1960);
DISPLAY 0.659574 (-1740 1960);
PAINT MONO (-1740 1960);
DISPLAY INVISIBLE (-1740 1960);
FORCEPROP 1 LASTPIN (-1750 1950) BN 4
J 2
(-1700 1960);
DISPLAY 0.617021 (-1700 1960);
PAINT PINK (-1700 1960);
FORCEPROP 2 LAST CDS_LIB mstr_standard
J 2
(-1700 1950);
DISPLAY 0.787234 (-1700 1950);
PAINT MONO (-1700 1950);
DISPLAY INVISIBLE (-1700 1950);
FORCEPROP 1 LAST BODY_TYPE PLUMBING
J 2
(-1700 1900);
DISPLAY 1.234043 (-1700 1900);
PAINT GREEN (-1700 1900);
DISPLAY INVISIBLE (-1700 1900);
FORCEPROP 1 LAST HDL_TAP TRUE
J 2
(-2025 1825);
DISPLAY 1.234043 (-2025 1825);
PAINT GREEN (-2025 1825);
DISPLAY INVISIBLE (-2025 1825);
FORCEPROP 1 LAST PATH I104
J 2
(-1700 1950);
DISPLAY 0.936170 (-1700 1950);
PAINT GREEN (-1700 1950);
DISPLAY INVISIBLE (-1700 1950);
FORCEADD TAP..6
R 2
(-1700 2000);
FORCEPROP 3 LASTPIN (-1750 2000) SIG_NAME M_K_DQ<7>
J 0
(-1740 2010);
DISPLAY 0.659574 (-1740 2010);
PAINT MONO (-1740 2010);
DISPLAY INVISIBLE (-1740 2010);
FORCEPROP 1 LASTPIN (-1750 2000) BN 7
J 2
(-1700 2010);
DISPLAY 0.617021 (-1700 2010);
PAINT PINK (-1700 2010);
FORCEPROP 2 LAST CDS_LIB mstr_standard
J 2
(-1700 2000);
DISPLAY 0.787234 (-1700 2000);
PAINT MONO (-1700 2000);
DISPLAY INVISIBLE (-1700 2000);
FORCEPROP 1 LAST BODY_TYPE PLUMBING
J 2
(-1700 1950);
DISPLAY 1.234043 (-1700 1950);
PAINT GREEN (-1700 1950);
DISPLAY INVISIBLE (-1700 1950);
FORCEPROP 1 LAST HDL_TAP TRUE
J 2
(-2025 1875);
DISPLAY 1.234043 (-2025 1875);
PAINT GREEN (-2025 1875);
DISPLAY INVISIBLE (-2025 1875);
FORCEPROP 1 LAST PATH I105
J 2
(-1700 2000);
DISPLAY 0.936170 (-1700 2000);
PAINT GREEN (-1700 2000);
DISPLAY INVISIBLE (-1700 2000);
FORCEADD TAP..6
R 2
(-1700 2100);
FORCEPROP 3 LASTPIN (-1750 2100) SIG_NAME M_K_DQ<9>
J 0
(-1740 2110);
DISPLAY 0.659574 (-1740 2110);
PAINT MONO (-1740 2110);
DISPLAY INVISIBLE (-1740 2110);
FORCEPROP 1 LASTPIN (-1750 2100) BN 9
J 2
(-1700 2110);
DISPLAY 0.617021 (-1700 2110);
PAINT PINK (-1700 2110);
FORCEPROP 2 LAST CDS_LIB mstr_standard
J 2
(-1700 2100);
DISPLAY 0.787234 (-1700 2100);
PAINT MONO (-1700 2100);
DISPLAY INVISIBLE (-1700 2100);
FORCEPROP 1 LAST BODY_TYPE PLUMBING
J 2
(-1700 2050);
DISPLAY 1.234043 (-1700 2050);
PAINT GREEN (-1700 2050);
DISPLAY INVISIBLE (-1700 2050);
FORCEPROP 1 LAST HDL_TAP TRUE
J 2
(-2025 1975);
DISPLAY 1.234043 (-2025 1975);
PAINT GREEN (-2025 1975);
DISPLAY INVISIBLE (-2025 1975);
FORCEPROP 1 LAST PATH I106
J 2
(-1700 2100);
DISPLAY 0.936170 (-1700 2100);
PAINT GREEN (-1700 2100);
DISPLAY INVISIBLE (-1700 2100);
FORCEADD TAP..6
R 2
(-1700 2050);
FORCEPROP 3 LASTPIN (-1750 2050) SIG_NAME M_K_DQ<6>
J 0
(-1740 2060);
DISPLAY 0.659574 (-1740 2060);
PAINT MONO (-1740 2060);
DISPLAY INVISIBLE (-1740 2060);
FORCEPROP 1 LASTPIN (-1750 2050) BN 6
J 2
(-1700 2060);
DISPLAY 0.617021 (-1700 2060);
PAINT PINK (-1700 2060);
FORCEPROP 2 LAST CDS_LIB mstr_standard
J 2
(-1700 2050);
DISPLAY 0.787234 (-1700 2050);
PAINT MONO (-1700 2050);
DISPLAY INVISIBLE (-1700 2050);
FORCEPROP 1 LAST BODY_TYPE PLUMBING
J 2
(-1700 2000);
DISPLAY 1.234043 (-1700 2000);
PAINT GREEN (-1700 2000);
DISPLAY INVISIBLE (-1700 2000);
FORCEPROP 1 LAST HDL_TAP TRUE
J 2
(-2025 1925);
DISPLAY 1.234043 (-2025 1925);
PAINT GREEN (-2025 1925);
DISPLAY INVISIBLE (-2025 1925);
FORCEPROP 1 LAST PATH I107
J 2
(-1700 2050);
DISPLAY 0.936170 (-1700 2050);
PAINT GREEN (-1700 2050);
DISPLAY INVISIBLE (-1700 2050);
FORCEADD TAP..6
R 2
(-1700 1700);
FORCEPROP 3 LASTPIN (-1750 1700) SIG_NAME M_K_DQ<1>
J 0
(-1740 1710);
DISPLAY 0.659574 (-1740 1710);
PAINT MONO (-1740 1710);
DISPLAY INVISIBLE (-1740 1710);
FORCEPROP 1 LASTPIN (-1750 1700) BN 1
J 2
(-1700 1710);
DISPLAY 0.617021 (-1700 1710);
PAINT PINK (-1700 1710);
FORCEPROP 2 LAST CDS_LIB mstr_standard
J 2
(-1700 1700);
DISPLAY 0.787234 (-1700 1700);
PAINT MONO (-1700 1700);
DISPLAY INVISIBLE (-1700 1700);
FORCEPROP 1 LAST BODY_TYPE PLUMBING
J 2
(-1700 1650);
DISPLAY 1.234043 (-1700 1650);
PAINT GREEN (-1700 1650);
DISPLAY INVISIBLE (-1700 1650);
FORCEPROP 1 LAST HDL_TAP TRUE
J 2
(-2025 1575);
DISPLAY 1.234043 (-2025 1575);
PAINT GREEN (-2025 1575);
DISPLAY INVISIBLE (-2025 1575);
FORCEPROP 1 LAST PATH I108
J 2
(-1700 1700);
DISPLAY 0.936170 (-1700 1700);
PAINT GREEN (-1700 1700);
DISPLAY INVISIBLE (-1700 1700);
FORCEADD TAP..6
R 2
(-1700 1800);
FORCEPROP 3 LASTPIN (-1750 1800) SIG_NAME M_K_DQ<3>
J 0
(-1740 1810);
DISPLAY 0.659574 (-1740 1810);
PAINT MONO (-1740 1810);
DISPLAY INVISIBLE (-1740 1810);
FORCEPROP 1 LASTPIN (-1750 1800) BN 3
J 2
(-1700 1810);
DISPLAY 0.617021 (-1700 1810);
PAINT PINK (-1700 1810);
FORCEPROP 2 LAST CDS_LIB mstr_standard
J 2
(-1700 1800);
DISPLAY 0.787234 (-1700 1800);
PAINT MONO (-1700 1800);
DISPLAY INVISIBLE (-1700 1800);
FORCEPROP 1 LAST BODY_TYPE PLUMBING
J 2
(-1700 1750);
DISPLAY 1.234043 (-1700 1750);
PAINT GREEN (-1700 1750);
DISPLAY INVISIBLE (-1700 1750);
FORCEPROP 1 LAST HDL_TAP TRUE
J 2
(-2025 1675);
DISPLAY 1.234043 (-2025 1675);
PAINT GREEN (-2025 1675);
DISPLAY INVISIBLE (-2025 1675);
FORCEPROP 1 LAST PATH I109
J 2
(-1700 1800);
DISPLAY 0.936170 (-1700 1800);
PAINT GREEN (-1700 1800);
DISPLAY INVISIBLE (-1700 1800);
FORCEADD TAP..6
R 2
(700 5000);
FORCEPROP 3 LASTPIN (650 5000) SIG_NAME M_K_DQS_DP<15>
J 0
(660 5010);
DISPLAY 0.659574 (660 5010);
PAINT MONO (660 5010);
DISPLAY INVISIBLE (660 5010);
FORCEPROP 1 LASTPIN (650 5000) BN 15
J 2
(700 5010);
DISPLAY 0.617021 (700 5010);
PAINT PINK (700 5010);
FORCEPROP 2 LAST CDS_LIB mstr_standard
J 0
(700 5000);
DISPLAY 0.787234 (700 5000);
PAINT MONO (700 5000);
DISPLAY INVISIBLE (700 5000);
FORCEPROP 1 LAST BODY_TYPE PLUMBING
J 2
(700 4950);
DISPLAY 1.234043 (700 4950);
PAINT GREEN (700 4950);
DISPLAY INVISIBLE (700 4950);
FORCEPROP 1 LAST HDL_TAP TRUE
J 2
(375 4875);
DISPLAY 1.234043 (375 4875);
PAINT GREEN (375 4875);
DISPLAY INVISIBLE (375 4875);
FORCEPROP 1 LAST PATH I11
J 2
(700 5000);
DISPLAY 0.936170 (700 5000);
PAINT GREEN (700 5000);
DISPLAY INVISIBLE (700 5000);
FORCEADD TAP..6
R 2
(-1700 1750);
FORCEPROP 3 LASTPIN (-1750 1750) SIG_NAME M_K_DQ<0>
J 0
(-1740 1760);
DISPLAY 0.659574 (-1740 1760);
PAINT MONO (-1740 1760);
DISPLAY INVISIBLE (-1740 1760);
FORCEPROP 1 LASTPIN (-1750 1750) BN 0
J 2
(-1700 1760);
DISPLAY 0.617021 (-1700 1760);
PAINT PINK (-1700 1760);
FORCEPROP 2 LAST CDS_LIB mstr_standard
J 2
(-1700 1750);
DISPLAY 0.787234 (-1700 1750);
PAINT MONO (-1700 1750);
DISPLAY INVISIBLE (-1700 1750);
FORCEPROP 1 LAST BODY_TYPE PLUMBING
J 2
(-1700 1700);
DISPLAY 1.234043 (-1700 1700);
PAINT GREEN (-1700 1700);
DISPLAY INVISIBLE (-1700 1700);
FORCEPROP 1 LAST HDL_TAP TRUE
J 2
(-2025 1625);
DISPLAY 1.234043 (-2025 1625);
PAINT GREEN (-2025 1625);
DISPLAY INVISIBLE (-2025 1625);
FORCEPROP 1 LAST PATH I110
J 2
(-1700 1750);
DISPLAY 0.936170 (-1700 1750);
PAINT GREEN (-1700 1750);
DISPLAY INVISIBLE (-1700 1750);
FORCEADD SCONN288_H44441004..1
(-2450 3200);
FORCEPROP 1 LAST LOCATION J1B1
J 0
(-2900 5100);
DISPLAY 0.617021 (-2900 5100);
PAINT AQUA (-2900 5100);
FORCEPROP 1 LAST PART_NUMBER H44441-004
J 0
(-2900 1200);
DISPLAY 0.617021 (-2900 1200);
PAINT BLUE (-2900 1200);
FORCEPROP 1 LAST MATERIAL SCONN
J 0
(-2900 5050);
DISPLAY 0.617021 (-2900 5050);
PAINT SKYBLUE (-2900 5050);
FORCEPROP 2 LASTPIN (-2950 1700) $PN 146
J 2
(-2960 1710);
DISPLAY 0.617021 (-2960 1710);
PAINT ORANGE (-2960 1710);
FORCEPROP 2 LASTPIN (-2950 2050) $PN 284
J 2
(-2960 2060);
DISPLAY 0.617021 (-2960 2060);
PAINT ORANGE (-2960 2060);
FORCEPROP 2 LASTPIN (-2950 1850) $PN 285
J 2
(-2960 1860);
DISPLAY 0.617021 (-2960 1860);
PAINT ORANGE (-2960 1860);
FORCEPROP 2 LASTPIN (-2950 1800) $PN 141
J 2
(-2960 1810);
DISPLAY 0.617021 (-2960 1810);
PAINT ORANGE (-2960 1810);
FORCEPROP 2 LASTPIN (-2950 1400) $PN 230
J 2
(-2960 1410);
DISPLAY 0.617021 (-2960 1410);
PAINT ORANGE (-2960 1410);
FORCEPROP 2 LASTPIN (-2950 2000) $PN 238
J 2
(-2960 2010);
DISPLAY 0.617021 (-2960 2010);
PAINT ORANGE (-2960 2010);
FORCEPROP 2 LASTPIN (-2950 1950) $PN 140
J 2
(-2960 1960);
DISPLAY 0.617021 (-2960 1960);
PAINT ORANGE (-2960 1960);
FORCEPROP 2 LASTPIN (-2950 1900) $PN 139
J 2
(-2960 1910);
DISPLAY 0.617021 (-2960 1910);
PAINT ORANGE (-2960 1910);
FORCEPROP 2 LASTPIN (-2950 3350) $PN 237
J 2
(-2960 3360);
DISPLAY 0.617021 (-2960 3360);
PAINT ORANGE (-2960 3360);
FORCEPROP 2 LASTPIN (-2950 3300) $PN 93
J 2
(-2960 3310);
DISPLAY 0.617021 (-2960 3310);
PAINT ORANGE (-2960 3310);
FORCEPROP 2 LASTPIN (-2950 3250) $PN 89
J 2
(-2960 3260);
DISPLAY 0.617021 (-2960 3260);
PAINT ORANGE (-2960 3260);
FORCEPROP 2 LASTPIN (-2950 3200) $PN 84
J 2
(-2960 3210);
DISPLAY 0.617021 (-2960 3210);
PAINT ORANGE (-2960 3210);
FORCEPROP 2 LASTPIN (-2950 1600) $PN 144
J 2
(-2960 1610);
DISPLAY 0.617021 (-2960 1610);
PAINT ORANGE (-2960 1610);
FORCEPROP 2 LASTPIN (-2950 1550) $PN 227
J 2
(-2960 1560);
DISPLAY 0.617021 (-2960 1560);
PAINT ORANGE (-2960 1560);
FORCEPROP 2 LASTPIN (-2950 1500) $PN 205
J 2
(-2960 1510);
DISPLAY 0.617021 (-2960 1510);
PAINT ORANGE (-2960 1510);
FORCEPROP 2 LASTPIN (-2950 2300) $PN 58
J 2
(-2960 2310);
DISPLAY 0.617021 (-2960 2310);
PAINT ORANGE (-2960 2310);
FORCEPROP 2 LASTPIN (-2950 2350) $PN 222
J 2
(-2960 2360);
DISPLAY 0.617021 (-2960 2360);
PAINT ORANGE (-2960 2360);
FORCEPROP 2 LASTPIN (-2950 2950) $PN 91
J 2
(-2960 2960);
DISPLAY 0.617021 (-2960 2960);
PAINT ORANGE (-2960 2960);
FORCEPROP 2 LASTPIN (-2950 2900) $PN 87
J 2
(-2960 2910);
DISPLAY 0.617021 (-2960 2910);
PAINT ORANGE (-2960 2910);
FORCEPROP 2 LASTPIN (-2950 2250) $PN 78
J 2
(-2960 2260);
DISPLAY 0.617021 (-2960 2260);
PAINT ORANGE (-2960 2260);
FORCEPROP 2 LASTPIN (-1950 4850) $PN 280
J 0
(-1940 4860);
DISPLAY 0.617021 (-1940 4860);
PAINT ORANGE (-1940 4860);
FORCEPROP 2 LASTPIN (-1950 4800) $PN 135
J 0
(-1940 4810);
DISPLAY 0.617021 (-1940 4810);
PAINT ORANGE (-1940 4810);
FORCEPROP 2 LASTPIN (-1950 4750) $PN 273
J 0
(-1940 4760);
DISPLAY 0.617021 (-1940 4760);
PAINT ORANGE (-1940 4760);
FORCEPROP 2 LASTPIN (-1950 4700) $PN 128
J 0
(-1940 4710);
DISPLAY 0.617021 (-1940 4710);
PAINT ORANGE (-1940 4710);
FORCEPROP 2 LASTPIN (-1950 4650) $PN 282
J 0
(-1940 4660);
DISPLAY 0.617021 (-1940 4660);
PAINT ORANGE (-1940 4660);
FORCEPROP 2 LASTPIN (-1950 4600) $PN 137
J 0
(-1940 4610);
DISPLAY 0.617021 (-1940 4610);
PAINT ORANGE (-1940 4610);
FORCEPROP 2 LASTPIN (-1950 4550) $PN 275
J 0
(-1940 4560);
DISPLAY 0.617021 (-1940 4560);
PAINT ORANGE (-1940 4560);
FORCEPROP 2 LASTPIN (-1950 4500) $PN 130
J 0
(-1940 4510);
DISPLAY 0.617021 (-1940 4510);
PAINT ORANGE (-1940 4510);
FORCEPROP 2 LASTPIN (-1950 4400) $PN 124
J 0
(-1940 4410);
DISPLAY 0.617021 (-1940 4410);
PAINT ORANGE (-1940 4410);
FORCEPROP 2 LASTPIN (-1950 4350) $PN 262
J 0
(-1940 4360);
DISPLAY 0.617021 (-1940 4360);
PAINT ORANGE (-1940 4360);
FORCEPROP 2 LASTPIN (-1950 4300) $PN 117
J 0
(-1940 4310);
DISPLAY 0.617021 (-1940 4310);
PAINT ORANGE (-1940 4310);
FORCEPROP 2 LASTPIN (-1950 4250) $PN 271
J 0
(-1940 4260);
DISPLAY 0.617021 (-1940 4260);
PAINT ORANGE (-1940 4260);
FORCEPROP 2 LASTPIN (-1950 4200) $PN 126
J 0
(-1940 4210);
DISPLAY 0.617021 (-1940 4210);
PAINT ORANGE (-1940 4210);
FORCEPROP 2 LASTPIN (-1950 4150) $PN 264
J 0
(-1940 4160);
DISPLAY 0.617021 (-1940 4160);
PAINT ORANGE (-1940 4160);
FORCEPROP 2 LASTPIN (-1950 4100) $PN 119
J 0
(-1940 4110);
DISPLAY 0.617021 (-1940 4110);
PAINT ORANGE (-1940 4110);
FORCEPROP 2 LASTPIN (-1950 4050) $PN 258
J 0
(-1940 4060);
DISPLAY 0.617021 (-1940 4060);
PAINT ORANGE (-1940 4060);
FORCEPROP 2 LASTPIN (-1950 4000) $PN 113
J 0
(-1940 4010);
DISPLAY 0.617021 (-1940 4010);
PAINT ORANGE (-1940 4010);
FORCEPROP 2 LASTPIN (-1950 3950) $PN 251
J 0
(-1940 3960);
DISPLAY 0.617021 (-1940 3960);
PAINT ORANGE (-1940 3960);
FORCEPROP 2 LASTPIN (-1950 3900) $PN 106
J 0
(-1940 3910);
DISPLAY 0.617021 (-1940 3910);
PAINT ORANGE (-1940 3910);
FORCEPROP 2 LASTPIN (-1950 3850) $PN 260
J 0
(-1940 3860);
DISPLAY 0.617021 (-1940 3860);
PAINT ORANGE (-1940 3860);
FORCEPROP 2 LASTPIN (-1950 3800) $PN 115
J 0
(-1940 3810);
DISPLAY 0.617021 (-1940 3810);
PAINT ORANGE (-1940 3810);
FORCEPROP 2 LASTPIN (-1950 3750) $PN 253
J 0
(-1940 3760);
DISPLAY 0.617021 (-1940 3760);
PAINT ORANGE (-1940 3760);
FORCEPROP 2 LASTPIN (-1950 3700) $PN 108
J 0
(-1940 3710);
DISPLAY 0.617021 (-1940 3710);
PAINT ORANGE (-1940 3710);
FORCEPROP 2 LASTPIN (-1950 3650) $PN 247
J 0
(-1940 3660);
DISPLAY 0.617021 (-1940 3660);
PAINT ORANGE (-1940 3660);
FORCEPROP 2 LASTPIN (-1950 3600) $PN 102
J 0
(-1940 3610);
DISPLAY 0.617021 (-1940 3610);
PAINT ORANGE (-1940 3610);
FORCEPROP 2 LASTPIN (-1950 3550) $PN 240
J 0
(-1940 3560);
DISPLAY 0.617021 (-1940 3560);
PAINT ORANGE (-1940 3560);
FORCEPROP 2 LASTPIN (-1950 3500) $PN 95
J 0
(-1940 3510);
DISPLAY 0.617021 (-1940 3510);
PAINT ORANGE (-1940 3510);
FORCEPROP 2 LASTPIN (-1950 3450) $PN 249
J 0
(-1940 3460);
DISPLAY 0.617021 (-1940 3460);
PAINT ORANGE (-1940 3460);
FORCEPROP 2 LASTPIN (-1950 3400) $PN 104
J 0
(-1940 3410);
DISPLAY 0.617021 (-1940 3410);
PAINT ORANGE (-1940 3410);
FORCEPROP 2 LASTPIN (-1950 3350) $PN 242
J 0
(-1940 3360);
DISPLAY 0.617021 (-1940 3360);
PAINT ORANGE (-1940 3360);
FORCEPROP 2 LASTPIN (-1950 3300) $PN 97
J 0
(-1940 3310);
DISPLAY 0.617021 (-1940 3310);
PAINT ORANGE (-1940 3310);
FORCEPROP 2 LASTPIN (-1950 3250) $PN 188
J 0
(-1940 3260);
DISPLAY 0.617021 (-1940 3260);
PAINT ORANGE (-1940 3260);
FORCEPROP 2 LASTPIN (-1950 3200) $PN 43
J 0
(-1940 3210);
DISPLAY 0.617021 (-1940 3210);
PAINT ORANGE (-1940 3210);
FORCEPROP 2 LASTPIN (-1950 3150) $PN 181
J 0
(-1940 3160);
DISPLAY 0.617021 (-1940 3160);
PAINT ORANGE (-1940 3160);
FORCEPROP 2 LASTPIN (-1950 3100) $PN 36
J 0
(-1940 3110);
DISPLAY 0.617021 (-1940 3110);
PAINT ORANGE (-1940 3110);
FORCEPROP 2 LASTPIN (-1950 3050) $PN 190
J 0
(-1940 3060);
DISPLAY 0.617021 (-1940 3060);
PAINT ORANGE (-1940 3060);
FORCEPROP 2 LASTPIN (-1950 3000) $PN 45
J 0
(-1940 3010);
DISPLAY 0.617021 (-1940 3010);
PAINT ORANGE (-1940 3010);
FORCEPROP 2 LASTPIN (-1950 2950) $PN 183
J 0
(-1940 2960);
DISPLAY 0.617021 (-1940 2960);
PAINT ORANGE (-1940 2960);
FORCEPROP 2 LASTPIN (-1950 2900) $PN 38
J 0
(-1940 2910);
DISPLAY 0.617021 (-1940 2910);
PAINT ORANGE (-1940 2910);
FORCEPROP 2 LASTPIN (-1950 2850) $PN 177
J 0
(-1940 2860);
DISPLAY 0.617021 (-1940 2860);
PAINT ORANGE (-1940 2860);
FORCEPROP 2 LASTPIN (-1950 2800) $PN 32
J 0
(-1940 2810);
DISPLAY 0.617021 (-1940 2810);
PAINT ORANGE (-1940 2810);
FORCEPROP 2 LASTPIN (-1950 2750) $PN 170
J 0
(-1940 2760);
DISPLAY 0.617021 (-1940 2760);
PAINT ORANGE (-1940 2760);
FORCEPROP 2 LASTPIN (-1950 2700) $PN 25
J 0
(-1940 2710);
DISPLAY 0.617021 (-1940 2710);
PAINT ORANGE (-1940 2710);
FORCEPROP 2 LASTPIN (-1950 2650) $PN 179
J 0
(-1940 2660);
DISPLAY 0.617021 (-1940 2660);
PAINT ORANGE (-1940 2660);
FORCEPROP 2 LASTPIN (-1950 2600) $PN 34
J 0
(-1940 2610);
DISPLAY 0.617021 (-1940 2610);
PAINT ORANGE (-1940 2610);
FORCEPROP 2 LASTPIN (-1950 2550) $PN 172
J 0
(-1940 2560);
DISPLAY 0.617021 (-1940 2560);
PAINT ORANGE (-1940 2560);
FORCEPROP 2 LASTPIN (-1950 2500) $PN 27
J 0
(-1940 2510);
DISPLAY 0.617021 (-1940 2510);
PAINT ORANGE (-1940 2510);
FORCEPROP 2 LASTPIN (-1950 2450) $PN 166
J 0
(-1940 2460);
DISPLAY 0.617021 (-1940 2460);
PAINT ORANGE (-1940 2460);
FORCEPROP 2 LASTPIN (-1950 2400) $PN 21
J 0
(-1940 2410);
DISPLAY 0.617021 (-1940 2410);
PAINT ORANGE (-1940 2410);
FORCEPROP 2 LASTPIN (-1950 2350) $PN 159
J 0
(-1940 2360);
DISPLAY 0.617021 (-1940 2360);
PAINT ORANGE (-1940 2360);
FORCEPROP 2 LASTPIN (-1950 2300) $PN 14
J 0
(-1940 2310);
DISPLAY 0.617021 (-1940 2310);
PAINT ORANGE (-1940 2310);
FORCEPROP 2 LASTPIN (-1950 2250) $PN 168
J 0
(-1940 2260);
DISPLAY 0.617021 (-1940 2260);
PAINT ORANGE (-1940 2260);
FORCEPROP 2 LASTPIN (-1950 2200) $PN 23
J 0
(-1940 2210);
DISPLAY 0.617021 (-1940 2210);
PAINT ORANGE (-1940 2210);
FORCEPROP 2 LASTPIN (-1950 2150) $PN 161
J 0
(-1940 2160);
DISPLAY 0.617021 (-1940 2160);
PAINT ORANGE (-1940 2160);
FORCEPROP 2 LASTPIN (-1950 2100) $PN 16
J 0
(-1940 2110);
DISPLAY 0.617021 (-1940 2110);
PAINT ORANGE (-1940 2110);
FORCEPROP 2 LASTPIN (-1950 2050) $PN 155
J 0
(-1940 2060);
DISPLAY 0.617021 (-1940 2060);
PAINT ORANGE (-1940 2060);
FORCEPROP 2 LASTPIN (-1950 2000) $PN 10
J 0
(-1940 2010);
DISPLAY 0.617021 (-1940 2010);
PAINT ORANGE (-1940 2010);
FORCEPROP 2 LASTPIN (-1950 1950) $PN 148
J 0
(-1940 1960);
DISPLAY 0.617021 (-1940 1960);
PAINT ORANGE (-1940 1960);
FORCEPROP 2 LASTPIN (-1950 1900) $PN 3
J 0
(-1940 1910);
DISPLAY 0.617021 (-1940 1910);
PAINT ORANGE (-1940 1910);
FORCEPROP 2 LASTPIN (-1950 1850) $PN 157
J 0
(-1940 1860);
DISPLAY 0.617021 (-1940 1860);
PAINT ORANGE (-1940 1860);
FORCEPROP 2 LASTPIN (-1950 1800) $PN 12
J 0
(-1940 1810);
DISPLAY 0.617021 (-1940 1810);
PAINT ORANGE (-1940 1810);
FORCEPROP 2 LASTPIN (-1950 1750) $PN 150
J 0
(-1940 1760);
DISPLAY 0.617021 (-1940 1760);
PAINT ORANGE (-1940 1760);
FORCEPROP 2 LASTPIN (-1950 1700) $PN 5
J 0
(-1940 1710);
DISPLAY 0.617021 (-1940 1710);
PAINT ORANGE (-1940 1710);
FORCEPROP 2 LASTPIN (-2950 3100) $PN 203
J 2
(-2960 3110);
DISPLAY 0.617021 (-2960 3110);
PAINT ORANGE (-2960 3110);
FORCEPROP 2 LASTPIN (-2950 3050) $PN 60
J 2
(-2960 3060);
DISPLAY 0.617021 (-2960 3060);
PAINT ORANGE (-2960 3060);
FORCEPROP 2 LASTPIN (-2950 3650) $PN 218
J 2
(-2960 3660);
DISPLAY 0.617021 (-2960 3660);
PAINT ORANGE (-2960 3660);
FORCEPROP 2 LASTPIN (-2950 3600) $PN 219
J 2
(-2960 3610);
DISPLAY 0.617021 (-2960 3610);
PAINT ORANGE (-2960 3610);
FORCEPROP 2 LASTPIN (-2950 3550) $PN 74
J 2
(-2960 3560);
DISPLAY 0.617021 (-2960 3560);
PAINT ORANGE (-2960 3560);
FORCEPROP 2 LASTPIN (-2950 3500) $PN 75
J 2
(-2960 3510);
DISPLAY 0.617021 (-2960 3510);
PAINT ORANGE (-2960 3510);
FORCEPROP 2 LASTPIN (-2950 2800) $PN 199
J 2
(-2960 2810);
DISPLAY 0.617021 (-2960 2810);
PAINT ORANGE (-2960 2810);
FORCEPROP 2 LASTPIN (-2950 2750) $PN 54
J 2
(-2960 2760);
DISPLAY 0.617021 (-2960 2760);
PAINT ORANGE (-2960 2760);
FORCEPROP 2 LASTPIN (-2950 2700) $PN 192
J 2
(-2960 2710);
DISPLAY 0.617021 (-2960 2710);
PAINT ORANGE (-2960 2710);
FORCEPROP 2 LASTPIN (-2950 2650) $PN 47
J 2
(-2960 2660);
DISPLAY 0.617021 (-2960 2660);
PAINT ORANGE (-2960 2660);
FORCEPROP 2 LASTPIN (-2950 2600) $PN 201
J 2
(-2960 2610);
DISPLAY 0.617021 (-2960 2610);
PAINT ORANGE (-2960 2610);
FORCEPROP 2 LASTPIN (-2950 2550) $PN 56
J 2
(-2960 2560);
DISPLAY 0.617021 (-2960 2560);
PAINT ORANGE (-2960 2560);
FORCEPROP 2 LASTPIN (-2950 2500) $PN 194
J 2
(-2960 2510);
DISPLAY 0.617021 (-2960 2510);
PAINT ORANGE (-2960 2510);
FORCEPROP 2 LASTPIN (-2950 2450) $PN 49
J 2
(-2960 2460);
DISPLAY 0.617021 (-2960 2460);
PAINT ORANGE (-2960 2460);
FORCEPROP 2 LASTPIN (-2950 3400) $PN 235
J 2
(-2960 3410);
DISPLAY 0.617021 (-2960 3410);
PAINT ORANGE (-2960 3410);
FORCEPROP 2 LASTPIN (-2950 3800) $PN 207
J 2
(-2960 3810);
DISPLAY 0.617021 (-2960 3810);
PAINT ORANGE (-2960 3810);
FORCEPROP 2 LASTPIN (-2950 3750) $PN 63
J 2
(-2960 3760);
DISPLAY 0.617021 (-2960 3760);
PAINT ORANGE (-2960 3760);
FORCEPROP 2 LASTPIN (-2950 3900) $PN 224
J 2
(-2960 3910);
DISPLAY 0.617021 (-2960 3910);
PAINT ORANGE (-2960 3910);
FORCEPROP 2 LASTPIN (-2950 3850) $PN 81
J 2
(-2960 3860);
DISPLAY 0.617021 (-2960 3860);
PAINT ORANGE (-2960 3860);
FORCEPROP 2 LASTPIN (-2950 2200) $PN 208
J 2
(-2960 2210);
DISPLAY 0.617021 (-2960 2210);
PAINT ORANGE (-2960 2210);
FORCEPROP 2 LASTPIN (-2950 2150) $PN 62
J 2
(-2960 2160);
DISPLAY 0.617021 (-2960 2160);
PAINT ORANGE (-2960 2160);
FORCEPROP 2 LASTPIN (-2950 4700) $PN 228
J 2
(-2960 4710);
DISPLAY 0.617021 (-2960 4710);
PAINT ORANGE (-2960 4710);
FORCEPROP 2 LASTPIN (-2950 4650) $PN 232
J 2
(-2960 4660);
DISPLAY 0.617021 (-2960 4660);
PAINT ORANGE (-2960 4660);
FORCEPROP 2 LASTPIN (-2950 4600) $PN 65
J 2
(-2960 4610);
DISPLAY 0.617021 (-2960 4610);
PAINT ORANGE (-2960 4610);
FORCEPROP 2 LASTPIN (-2950 4550) $PN 210
J 2
(-2960 4560);
DISPLAY 0.617021 (-2960 4560);
PAINT ORANGE (-2960 4560);
FORCEPROP 2 LASTPIN (-2950 4500) $PN 225
J 2
(-2960 4510);
DISPLAY 0.617021 (-2960 4510);
PAINT ORANGE (-2960 4510);
FORCEPROP 2 LASTPIN (-2950 4450) $PN 66
J 2
(-2960 4460);
DISPLAY 0.617021 (-2960 4460);
PAINT ORANGE (-2960 4460);
FORCEPROP 2 LASTPIN (-2950 4400) $PN 68
J 2
(-2960 4410);
DISPLAY 0.617021 (-2960 4410);
PAINT ORANGE (-2960 4410);
FORCEPROP 2 LASTPIN (-2950 4350) $PN 211
J 2
(-2960 4360);
DISPLAY 0.617021 (-2960 4360);
PAINT ORANGE (-2960 4360);
FORCEPROP 2 LASTPIN (-2950 4300) $PN 69
J 2
(-2960 4310);
DISPLAY 0.617021 (-2960 4310);
PAINT ORANGE (-2960 4310);
FORCEPROP 2 LASTPIN (-2950 4250) $PN 213
J 2
(-2960 4260);
DISPLAY 0.617021 (-2960 4260);
PAINT ORANGE (-2960 4260);
FORCEPROP 2 LASTPIN (-2950 4200) $PN 214
J 2
(-2960 4210);
DISPLAY 0.617021 (-2960 4210);
PAINT ORANGE (-2960 4210);
FORCEPROP 2 LASTPIN (-2950 4150) $PN 71
J 2
(-2960 4160);
DISPLAY 0.617021 (-2960 4160);
PAINT ORANGE (-2960 4160);
FORCEPROP 2 LASTPIN (-2950 4100) $PN 216
J 2
(-2960 4110);
DISPLAY 0.617021 (-2960 4110);
PAINT ORANGE (-2960 4110);
FORCEPROP 2 LASTPIN (-2950 4050) $PN 72
J 2
(-2960 4060);
DISPLAY 0.617021 (-2960 4060);
PAINT ORANGE (-2960 4060);
FORCEPROP 2 LASTPIN (-2950 4000) $PN 79
J 2
(-2960 4010);
DISPLAY 0.617021 (-2960 4010);
PAINT ORANGE (-2960 4010);
FORCEPROP 2 LASTPIN (-2950 4850) $PN 234
J 2
(-2960 4860);
DISPLAY 0.617021 (-2960 4860);
PAINT ORANGE (-2960 4860);
FORCEPROP 2 LASTPIN (-1950 4450) $PN 269
J 0
(-1940 4460);
DISPLAY 0.617021 (-1940 4460);
PAINT ORANGE (-1940 4460);
FORCEPROP 2 LASTPIN (-2950 4800) $PN 82
J 2
(-2960 4810);
DISPLAY 0.617021 (-2960 4810);
PAINT ORANGE (-2960 4810);
FORCEPROP 2 LASTPIN (-2950 4750) $PN 86
J 2
(-2960 4760);
DISPLAY 0.617021 (-2960 4760);
PAINT ORANGE (-2960 4760);
FORCEPROP 1 LAST PACK_TYPE PIP
J 0
(-2900 5150);
PAINT SKYBLUE (-2900 5150);
DISPLAY INVISIBLE (-2900 5150);
FORCEPROP 2 LAST BOM_COST MEM
J 0
(-2450 3200);
PAINT ORANGE (-2450 3200);
DISPLAY INVISIBLE (-2450 3200);
FORCEPROP 2 LAST CDS_LIB mstr_sconn
J 0
(-2450 3200);
PAINT ORANGE (-2450 3200);
DISPLAY INVISIBLE (-2450 3200);
FORCEPROP 2 LAST SEC_TYPE PIP
J 0
(-2900 5150);
DISPLAY 1.021277 (-2900 5150);
PAINT ORANGE (-2900 5150);
DISPLAY INVISIBLE (-2900 5150);
FORCEPROP 2 LAST SEC 1
J 0
(-2900 5150);
DISPLAY 0.680851 (-2900 5150);
PAINT MONO (-2900 5150);
DISPLAY INVISIBLE (-2900 5150);
FORCEPROP 2 LAST CDS_LOCATION J1B1
J 0
(-2900 5100);
DISPLAY 0.617021 (-2900 5100);
PAINT AQUA (-2900 5100);
DISPLAY INVISIBLE (-2900 5100);
FORCEPROP 1 LAST PATH I111
J 0
(-2450 5050);
PAINT GREEN (-2450 5050);
DISPLAY INVISIBLE (-2450 5050);
FORCEPROP 2 LAST ROOM DDR4_CH_K
J 0
(-2450 3200);
PAINT ORANGE (-2450 3200);
DISPLAY INVISIBLE (-2450 3200);
FORCEADD TAP..6
(-3200 4800);
FORCEPROP 3 LASTPIN (-3150 4800) SIG_NAME M_K_MA<16>
J 0
(-3140 4810);
DISPLAY 0.659574 (-3140 4810);
PAINT MONO (-3140 4810);
DISPLAY INVISIBLE (-3140 4810);
FORCEPROP 1 LASTPIN (-3150 4800) BN 16
J 0
(-3200 4810);
DISPLAY 0.617021 (-3200 4810);
PAINT PINK (-3200 4810);
FORCEPROP 2 LAST CDS_LIB mstr_standard
J 2
(-3200 4800);
DISPLAY 0.787234 (-3200 4800);
PAINT MONO (-3200 4800);
DISPLAY INVISIBLE (-3200 4800);
FORCEPROP 1 LAST BODY_TYPE PLUMBING
J 0
(-3200 4750);
DISPLAY 1.234043 (-3200 4750);
PAINT GREEN (-3200 4750);
DISPLAY INVISIBLE (-3200 4750);
FORCEPROP 1 LAST HDL_TAP TRUE
J 0
(-2875 4675);
DISPLAY 1.234043 (-2875 4675);
PAINT GREEN (-2875 4675);
DISPLAY INVISIBLE (-2875 4675);
FORCEPROP 1 LAST PATH I112
J 0
(-3200 4800);
DISPLAY 0.936170 (-3200 4800);
PAINT GREEN (-3200 4800);
DISPLAY INVISIBLE (-3200 4800);
FORCEADD TAP..6
(-3200 4850);
FORCEPROP 3 LASTPIN (-3150 4850) SIG_NAME M_K_MA<17>
J 0
(-3140 4860);
DISPLAY 0.659574 (-3140 4860);
PAINT MONO (-3140 4860);
DISPLAY INVISIBLE (-3140 4860);
FORCEPROP 1 LASTPIN (-3150 4850) BN 17
J 0
(-3200 4860);
DISPLAY 0.617021 (-3200 4860);
PAINT PINK (-3200 4860);
FORCEPROP 2 LAST CDS_LIB mstr_standard
J 0
(-3200 4850);
DISPLAY 0.787234 (-3200 4850);
PAINT MONO (-3200 4850);
DISPLAY INVISIBLE (-3200 4850);
FORCEPROP 1 LAST BODY_TYPE PLUMBING
J 0
(-3200 4800);
DISPLAY 1.234043 (-3200 4800);
PAINT GREEN (-3200 4800);
DISPLAY INVISIBLE (-3200 4800);
FORCEPROP 1 LAST HDL_TAP TRUE
J 0
(-2875 4725);
DISPLAY 1.234043 (-2875 4725);
PAINT GREEN (-2875 4725);
DISPLAY INVISIBLE (-2875 4725);
FORCEPROP 1 LAST PATH I113
J 0
(-3200 4850);
DISPLAY 0.936170 (-3200 4850);
PAINT GREEN (-3200 4850);
DISPLAY INVISIBLE (-3200 4850);
FORCEADD TAP..6
(-3200 4750);
FORCEPROP 3 LASTPIN (-3150 4750) SIG_NAME M_K_MA<15>
J 0
(-3140 4760);
DISPLAY 0.659574 (-3140 4760);
PAINT MONO (-3140 4760);
DISPLAY INVISIBLE (-3140 4760);
FORCEPROP 1 LASTPIN (-3150 4750) BN 15
J 0
(-3200 4760);
DISPLAY 0.617021 (-3200 4760);
PAINT PINK (-3200 4760);
FORCEPROP 2 LAST CDS_LIB mstr_standard
J 2
(-3200 4750);
DISPLAY 0.787234 (-3200 4750);
PAINT MONO (-3200 4750);
DISPLAY INVISIBLE (-3200 4750);
FORCEPROP 1 LAST BODY_TYPE PLUMBING
J 0
(-3200 4700);
DISPLAY 1.234043 (-3200 4700);
PAINT GREEN (-3200 4700);
DISPLAY INVISIBLE (-3200 4700);
FORCEPROP 1 LAST HDL_TAP TRUE
J 0
(-2875 4625);
DISPLAY 1.234043 (-2875 4625);
PAINT GREEN (-2875 4625);
DISPLAY INVISIBLE (-2875 4625);
FORCEPROP 1 LAST PATH I114
J 0
(-3200 4750);
DISPLAY 0.936170 (-3200 4750);
PAINT GREEN (-3200 4750);
DISPLAY INVISIBLE (-3200 4750);
FORCEADD TAP..6
(-3200 4700);
FORCEPROP 3 LASTPIN (-3150 4700) SIG_NAME M_K_MA<14>
J 0
(-3140 4710);
DISPLAY 0.659574 (-3140 4710);
PAINT MONO (-3140 4710);
DISPLAY INVISIBLE (-3140 4710);
FORCEPROP 1 LASTPIN (-3150 4700) BN 14
J 0
(-3200 4710);
DISPLAY 0.617021 (-3200 4710);
PAINT PINK (-3200 4710);
FORCEPROP 2 LAST CDS_LIB mstr_standard
J 2
(-3200 4700);
DISPLAY 0.787234 (-3200 4700);
PAINT MONO (-3200 4700);
DISPLAY INVISIBLE (-3200 4700);
FORCEPROP 1 LAST BODY_TYPE PLUMBING
J 0
(-3200 4650);
DISPLAY 1.234043 (-3200 4650);
PAINT GREEN (-3200 4650);
DISPLAY INVISIBLE (-3200 4650);
FORCEPROP 1 LAST HDL_TAP TRUE
J 0
(-2875 4575);
DISPLAY 1.234043 (-2875 4575);
PAINT GREEN (-2875 4575);
DISPLAY INVISIBLE (-2875 4575);
FORCEPROP 1 LAST PATH I115
J 0
(-3200 4700);
DISPLAY 0.936170 (-3200 4700);
PAINT GREEN (-3200 4700);
DISPLAY INVISIBLE (-3200 4700);
FORCEADD TAP..6
(-3200 4650);
FORCEPROP 3 LASTPIN (-3150 4650) SIG_NAME M_K_MA<13>
J 0
(-3140 4660);
DISPLAY 0.659574 (-3140 4660);
PAINT MONO (-3140 4660);
DISPLAY INVISIBLE (-3140 4660);
FORCEPROP 1 LASTPIN (-3150 4650) BN 13
J 0
(-3200 4660);
DISPLAY 0.617021 (-3200 4660);
PAINT PINK (-3200 4660);
FORCEPROP 2 LAST CDS_LIB mstr_standard
J 2
(-3200 4650);
DISPLAY 0.787234 (-3200 4650);
PAINT MONO (-3200 4650);
DISPLAY INVISIBLE (-3200 4650);
FORCEPROP 1 LAST BODY_TYPE PLUMBING
J 0
(-3200 4600);
DISPLAY 1.234043 (-3200 4600);
PAINT GREEN (-3200 4600);
DISPLAY INVISIBLE (-3200 4600);
FORCEPROP 1 LAST HDL_TAP TRUE
J 0
(-2875 4525);
DISPLAY 1.234043 (-2875 4525);
PAINT GREEN (-2875 4525);
DISPLAY INVISIBLE (-2875 4525);
FORCEPROP 1 LAST PATH I116
J 0
(-3200 4650);
DISPLAY 0.936170 (-3200 4650);
PAINT GREEN (-3200 4650);
DISPLAY INVISIBLE (-3200 4650);
FORCEADD TAP..6
(-3200 4600);
FORCEPROP 3 LASTPIN (-3150 4600) SIG_NAME M_K_MA<12>
J 0
(-3140 4610);
DISPLAY 0.659574 (-3140 4610);
PAINT MONO (-3140 4610);
DISPLAY INVISIBLE (-3140 4610);
FORCEPROP 1 LASTPIN (-3150 4600) BN 12
J 0
(-3200 4610);
DISPLAY 0.617021 (-3200 4610);
PAINT PINK (-3200 4610);
FORCEPROP 2 LAST CDS_LIB mstr_standard
J 2
(-3200 4600);
DISPLAY 0.787234 (-3200 4600);
PAINT MONO (-3200 4600);
DISPLAY INVISIBLE (-3200 4600);
FORCEPROP 1 LAST BODY_TYPE PLUMBING
J 0
(-3200 4550);
DISPLAY 1.234043 (-3200 4550);
PAINT GREEN (-3200 4550);
DISPLAY INVISIBLE (-3200 4550);
FORCEPROP 1 LAST HDL_TAP TRUE
J 0
(-2875 4475);
DISPLAY 1.234043 (-2875 4475);
PAINT GREEN (-2875 4475);
DISPLAY INVISIBLE (-2875 4475);
FORCEPROP 1 LAST PATH I117
J 0
(-3200 4600);
DISPLAY 0.936170 (-3200 4600);
PAINT GREEN (-3200 4600);
DISPLAY INVISIBLE (-3200 4600);
FORCEADD TAP..6
(-3200 4550);
FORCEPROP 3 LASTPIN (-3150 4550) SIG_NAME M_K_MA<11>
J 0
(-3140 4560);
DISPLAY 0.659574 (-3140 4560);
PAINT MONO (-3140 4560);
DISPLAY INVISIBLE (-3140 4560);
FORCEPROP 1 LASTPIN (-3150 4550) BN 11
J 0
(-3200 4560);
DISPLAY 0.617021 (-3200 4560);
PAINT PINK (-3200 4560);
FORCEPROP 2 LAST CDS_LIB mstr_standard
J 2
(-3200 4550);
DISPLAY 0.787234 (-3200 4550);
PAINT MONO (-3200 4550);
DISPLAY INVISIBLE (-3200 4550);
FORCEPROP 1 LAST BODY_TYPE PLUMBING
J 0
(-3200 4500);
DISPLAY 1.234043 (-3200 4500);
PAINT GREEN (-3200 4500);
DISPLAY INVISIBLE (-3200 4500);
FORCEPROP 1 LAST HDL_TAP TRUE
J 0
(-2875 4425);
DISPLAY 1.234043 (-2875 4425);
PAINT GREEN (-2875 4425);
DISPLAY INVISIBLE (-2875 4425);
FORCEPROP 1 LAST PATH I118
J 0
(-3200 4550);
DISPLAY 0.936170 (-3200 4550);
PAINT GREEN (-3200 4550);
DISPLAY INVISIBLE (-3200 4550);
FORCEADD TAP..6
(-3200 4500);
FORCEPROP 3 LASTPIN (-3150 4500) SIG_NAME M_K_MA<10>
J 0
(-3140 4510);
DISPLAY 0.659574 (-3140 4510);
PAINT MONO (-3140 4510);
DISPLAY INVISIBLE (-3140 4510);
FORCEPROP 1 LASTPIN (-3150 4500) BN 10
J 0
(-3200 4510);
DISPLAY 0.617021 (-3200 4510);
PAINT PINK (-3200 4510);
FORCEPROP 2 LAST CDS_LIB mstr_standard
J 2
(-3200 4500);
DISPLAY 0.787234 (-3200 4500);
PAINT MONO (-3200 4500);
DISPLAY INVISIBLE (-3200 4500);
FORCEPROP 1 LAST BODY_TYPE PLUMBING
J 0
(-3200 4450);
DISPLAY 1.234043 (-3200 4450);
PAINT GREEN (-3200 4450);
DISPLAY INVISIBLE (-3200 4450);
FORCEPROP 1 LAST HDL_TAP TRUE
J 0
(-2875 4375);
DISPLAY 1.234043 (-2875 4375);
PAINT GREEN (-2875 4375);
DISPLAY INVISIBLE (-2875 4375);
FORCEPROP 1 LAST PATH I119
J 0
(-3200 4500);
DISPLAY 0.936170 (-3200 4500);
PAINT GREEN (-3200 4500);
DISPLAY INVISIBLE (-3200 4500);
FORCEADD TAP..6
R 2
(700 5100);
FORCEPROP 3 LASTPIN (650 5100) SIG_NAME M_K_DQS_DP<16>
J 0
(660 5110);
DISPLAY 0.659574 (660 5110);
PAINT MONO (660 5110);
DISPLAY INVISIBLE (660 5110);
FORCEPROP 1 LASTPIN (650 5100) BN 16
J 2
(700 5110);
DISPLAY 0.617021 (700 5110);
PAINT PINK (700 5110);
FORCEPROP 2 LAST CDS_LIB mstr_standard
J 0
(700 5100);
DISPLAY 0.787234 (700 5100);
PAINT MONO (700 5100);
DISPLAY INVISIBLE (700 5100);
FORCEPROP 1 LAST BODY_TYPE PLUMBING
J 2
(700 5050);
DISPLAY 1.234043 (700 5050);
PAINT GREEN (700 5050);
DISPLAY INVISIBLE (700 5050);
FORCEPROP 1 LAST HDL_TAP TRUE
J 2
(375 4975);
DISPLAY 1.234043 (375 4975);
PAINT GREEN (375 4975);
DISPLAY INVISIBLE (375 4975);
FORCEPROP 1 LAST PATH I12
J 2
(700 5100);
DISPLAY 0.936170 (700 5100);
PAINT GREEN (700 5100);
DISPLAY INVISIBLE (700 5100);
FORCEADD TAP..6
(-3200 4450);
FORCEPROP 3 LASTPIN (-3150 4450) SIG_NAME M_K_MA<9>
J 0
(-3140 4460);
DISPLAY 0.659574 (-3140 4460);
PAINT MONO (-3140 4460);
DISPLAY INVISIBLE (-3140 4460);
FORCEPROP 1 LASTPIN (-3150 4450) BN 9
J 0
(-3200 4460);
DISPLAY 0.617021 (-3200 4460);
PAINT PINK (-3200 4460);
FORCEPROP 2 LAST CDS_LIB mstr_standard
J 2
(-3200 4450);
DISPLAY 0.787234 (-3200 4450);
PAINT MONO (-3200 4450);
DISPLAY INVISIBLE (-3200 4450);
FORCEPROP 1 LAST BODY_TYPE PLUMBING
J 0
(-3200 4400);
DISPLAY 1.234043 (-3200 4400);
PAINT GREEN (-3200 4400);
DISPLAY INVISIBLE (-3200 4400);
FORCEPROP 1 LAST HDL_TAP TRUE
J 0
(-2875 4325);
DISPLAY 1.234043 (-2875 4325);
PAINT GREEN (-2875 4325);
DISPLAY INVISIBLE (-2875 4325);
FORCEPROP 1 LAST PATH I120
J 0
(-3200 4450);
DISPLAY 0.936170 (-3200 4450);
PAINT GREEN (-3200 4450);
DISPLAY INVISIBLE (-3200 4450);
FORCEADD TAP..6
(-3200 4400);
FORCEPROP 3 LASTPIN (-3150 4400) SIG_NAME M_K_MA<8>
J 0
(-3140 4410);
DISPLAY 0.659574 (-3140 4410);
PAINT MONO (-3140 4410);
DISPLAY INVISIBLE (-3140 4410);
FORCEPROP 1 LASTPIN (-3150 4400) BN 8
J 0
(-3200 4410);
DISPLAY 0.617021 (-3200 4410);
PAINT PINK (-3200 4410);
FORCEPROP 2 LAST CDS_LIB mstr_standard
J 2
(-3200 4400);
DISPLAY 0.787234 (-3200 4400);
PAINT MONO (-3200 4400);
DISPLAY INVISIBLE (-3200 4400);
FORCEPROP 1 LAST BODY_TYPE PLUMBING
J 0
(-3200 4350);
DISPLAY 1.234043 (-3200 4350);
PAINT GREEN (-3200 4350);
DISPLAY INVISIBLE (-3200 4350);
FORCEPROP 1 LAST HDL_TAP TRUE
J 0
(-2875 4275);
DISPLAY 1.234043 (-2875 4275);
PAINT GREEN (-2875 4275);
DISPLAY INVISIBLE (-2875 4275);
FORCEPROP 1 LAST PATH I121
J 0
(-3200 4400);
DISPLAY 0.936170 (-3200 4400);
PAINT GREEN (-3200 4400);
DISPLAY INVISIBLE (-3200 4400);
FORCEADD TAP..6
(-3200 4350);
FORCEPROP 3 LASTPIN (-3150 4350) SIG_NAME M_K_MA<7>
J 0
(-3140 4360);
DISPLAY 0.659574 (-3140 4360);
PAINT MONO (-3140 4360);
DISPLAY INVISIBLE (-3140 4360);
FORCEPROP 1 LASTPIN (-3150 4350) BN 7
J 0
(-3200 4360);
DISPLAY 0.617021 (-3200 4360);
PAINT PINK (-3200 4360);
FORCEPROP 2 LAST CDS_LIB mstr_standard
J 2
(-3200 4350);
DISPLAY 0.787234 (-3200 4350);
PAINT MONO (-3200 4350);
DISPLAY INVISIBLE (-3200 4350);
FORCEPROP 1 LAST BODY_TYPE PLUMBING
J 0
(-3200 4300);
DISPLAY 1.234043 (-3200 4300);
PAINT GREEN (-3200 4300);
DISPLAY INVISIBLE (-3200 4300);
FORCEPROP 1 LAST HDL_TAP TRUE
J 0
(-2875 4225);
DISPLAY 1.234043 (-2875 4225);
PAINT GREEN (-2875 4225);
DISPLAY INVISIBLE (-2875 4225);
FORCEPROP 1 LAST PATH I122
J 0
(-3200 4350);
DISPLAY 0.936170 (-3200 4350);
PAINT GREEN (-3200 4350);
DISPLAY INVISIBLE (-3200 4350);
FORCEADD TAP..6
(-3200 4300);
FORCEPROP 3 LASTPIN (-3150 4300) SIG_NAME M_K_MA<6>
J 0
(-3140 4310);
DISPLAY 0.659574 (-3140 4310);
PAINT MONO (-3140 4310);
DISPLAY INVISIBLE (-3140 4310);
FORCEPROP 1 LASTPIN (-3150 4300) BN 6
J 0
(-3200 4310);
DISPLAY 0.617021 (-3200 4310);
PAINT PINK (-3200 4310);
FORCEPROP 2 LAST CDS_LIB mstr_standard
J 2
(-3200 4300);
DISPLAY 0.787234 (-3200 4300);
PAINT MONO (-3200 4300);
DISPLAY INVISIBLE (-3200 4300);
FORCEPROP 1 LAST BODY_TYPE PLUMBING
J 0
(-3200 4250);
DISPLAY 1.234043 (-3200 4250);
PAINT GREEN (-3200 4250);
DISPLAY INVISIBLE (-3200 4250);
FORCEPROP 1 LAST HDL_TAP TRUE
J 0
(-2875 4175);
DISPLAY 1.234043 (-2875 4175);
PAINT GREEN (-2875 4175);
DISPLAY INVISIBLE (-2875 4175);
FORCEPROP 1 LAST PATH I123
J 0
(-3200 4300);
DISPLAY 0.936170 (-3200 4300);
PAINT GREEN (-3200 4300);
DISPLAY INVISIBLE (-3200 4300);
FORCEADD TAP..6
(-3200 4250);
FORCEPROP 3 LASTPIN (-3150 4250) SIG_NAME M_K_MA<5>
J 0
(-3140 4260);
DISPLAY 0.659574 (-3140 4260);
PAINT MONO (-3140 4260);
DISPLAY INVISIBLE (-3140 4260);
FORCEPROP 1 LASTPIN (-3150 4250) BN 5
J 0
(-3200 4260);
DISPLAY 0.617021 (-3200 4260);
PAINT PINK (-3200 4260);
FORCEPROP 2 LAST CDS_LIB mstr_standard
J 2
(-3200 4250);
DISPLAY 0.787234 (-3200 4250);
PAINT MONO (-3200 4250);
DISPLAY INVISIBLE (-3200 4250);
FORCEPROP 1 LAST BODY_TYPE PLUMBING
J 0
(-3200 4200);
DISPLAY 1.234043 (-3200 4200);
PAINT GREEN (-3200 4200);
DISPLAY INVISIBLE (-3200 4200);
FORCEPROP 1 LAST HDL_TAP TRUE
J 0
(-2875 4125);
DISPLAY 1.234043 (-2875 4125);
PAINT GREEN (-2875 4125);
DISPLAY INVISIBLE (-2875 4125);
FORCEPROP 1 LAST PATH I124
J 0
(-3200 4250);
DISPLAY 0.936170 (-3200 4250);
PAINT GREEN (-3200 4250);
DISPLAY INVISIBLE (-3200 4250);
FORCEADD TAP..6
(-3200 4200);
FORCEPROP 3 LASTPIN (-3150 4200) SIG_NAME M_K_MA<4>
J 0
(-3140 4210);
DISPLAY 0.659574 (-3140 4210);
PAINT MONO (-3140 4210);
DISPLAY INVISIBLE (-3140 4210);
FORCEPROP 1 LASTPIN (-3150 4200) BN 4
J 0
(-3200 4210);
DISPLAY 0.617021 (-3200 4210);
PAINT PINK (-3200 4210);
FORCEPROP 2 LAST CDS_LIB mstr_standard
J 2
(-3200 4200);
DISPLAY 0.787234 (-3200 4200);
PAINT MONO (-3200 4200);
DISPLAY INVISIBLE (-3200 4200);
FORCEPROP 1 LAST BODY_TYPE PLUMBING
J 0
(-3200 4150);
DISPLAY 1.234043 (-3200 4150);
PAINT GREEN (-3200 4150);
DISPLAY INVISIBLE (-3200 4150);
FORCEPROP 1 LAST HDL_TAP TRUE
J 0
(-2875 4075);
DISPLAY 1.234043 (-2875 4075);
PAINT GREEN (-2875 4075);
DISPLAY INVISIBLE (-2875 4075);
FORCEPROP 1 LAST PATH I125
J 0
(-3200 4200);
DISPLAY 0.936170 (-3200 4200);
PAINT GREEN (-3200 4200);
DISPLAY INVISIBLE (-3200 4200);
FORCEADD TAP..6
(-3200 4100);
FORCEPROP 3 LASTPIN (-3150 4100) SIG_NAME M_K_MA<2>
J 0
(-3140 4110);
DISPLAY 0.659574 (-3140 4110);
PAINT MONO (-3140 4110);
DISPLAY INVISIBLE (-3140 4110);
FORCEPROP 1 LASTPIN (-3150 4100) BN 2
J 0
(-3200 4110);
DISPLAY 0.617021 (-3200 4110);
PAINT PINK (-3200 4110);
FORCEPROP 2 LAST CDS_LIB mstr_standard
J 2
(-3200 4100);
DISPLAY 0.787234 (-3200 4100);
PAINT MONO (-3200 4100);
DISPLAY INVISIBLE (-3200 4100);
FORCEPROP 1 LAST BODY_TYPE PLUMBING
J 0
(-3200 4050);
DISPLAY 1.234043 (-3200 4050);
PAINT GREEN (-3200 4050);
DISPLAY INVISIBLE (-3200 4050);
FORCEPROP 1 LAST HDL_TAP TRUE
J 0
(-2875 3975);
DISPLAY 1.234043 (-2875 3975);
PAINT GREEN (-2875 3975);
DISPLAY INVISIBLE (-2875 3975);
FORCEPROP 1 LAST PATH I126
J 0
(-3200 4100);
DISPLAY 0.936170 (-3200 4100);
PAINT GREEN (-3200 4100);
DISPLAY INVISIBLE (-3200 4100);
FORCEADD TAP..6
(-3200 4150);
FORCEPROP 3 LASTPIN (-3150 4150) SIG_NAME M_K_MA<3>
J 0
(-3140 4160);
DISPLAY 0.659574 (-3140 4160);
PAINT MONO (-3140 4160);
DISPLAY INVISIBLE (-3140 4160);
FORCEPROP 1 LASTPIN (-3150 4150) BN 3
J 0
(-3200 4160);
DISPLAY 0.617021 (-3200 4160);
PAINT PINK (-3200 4160);
FORCEPROP 2 LAST CDS_LIB mstr_standard
J 2
(-3200 4150);
DISPLAY 0.787234 (-3200 4150);
PAINT MONO (-3200 4150);
DISPLAY INVISIBLE (-3200 4150);
FORCEPROP 1 LAST BODY_TYPE PLUMBING
J 0
(-3200 4100);
DISPLAY 1.234043 (-3200 4100);
PAINT GREEN (-3200 4100);
DISPLAY INVISIBLE (-3200 4100);
FORCEPROP 1 LAST HDL_TAP TRUE
J 0
(-2875 4025);
DISPLAY 1.234043 (-2875 4025);
PAINT GREEN (-2875 4025);
DISPLAY INVISIBLE (-2875 4025);
FORCEPROP 1 LAST PATH I127
J 0
(-3200 4150);
DISPLAY 0.936170 (-3200 4150);
PAINT GREEN (-3200 4150);
DISPLAY INVISIBLE (-3200 4150);
FORCEADD TAP..6
(-3200 4050);
FORCEPROP 3 LASTPIN (-3150 4050) SIG_NAME M_K_MA<1>
J 0
(-3140 4060);
DISPLAY 0.659574 (-3140 4060);
PAINT MONO (-3140 4060);
DISPLAY INVISIBLE (-3140 4060);
FORCEPROP 1 LASTPIN (-3150 4050) BN 1
J 0
(-3200 4060);
DISPLAY 0.617021 (-3200 4060);
PAINT PINK (-3200 4060);
FORCEPROP 2 LAST CDS_LIB mstr_standard
J 2
(-3200 4050);
DISPLAY 0.787234 (-3200 4050);
PAINT MONO (-3200 4050);
DISPLAY INVISIBLE (-3200 4050);
FORCEPROP 1 LAST BODY_TYPE PLUMBING
J 0
(-3200 4000);
DISPLAY 1.234043 (-3200 4000);
PAINT GREEN (-3200 4000);
DISPLAY INVISIBLE (-3200 4000);
FORCEPROP 1 LAST HDL_TAP TRUE
J 0
(-2875 3925);
DISPLAY 1.234043 (-2875 3925);
PAINT GREEN (-2875 3925);
DISPLAY INVISIBLE (-2875 3925);
FORCEPROP 1 LAST PATH I128
J 0
(-3200 4050);
DISPLAY 0.936170 (-3200 4050);
PAINT GREEN (-3200 4050);
DISPLAY INVISIBLE (-3200 4050);
FORCEADD TAP..6
(-3200 4000);
FORCEPROP 3 LASTPIN (-3150 4000) SIG_NAME M_K_MA<0>
J 0
(-3140 4010);
DISPLAY 0.659574 (-3140 4010);
PAINT MONO (-3140 4010);
DISPLAY INVISIBLE (-3140 4010);
FORCEPROP 1 LASTPIN (-3150 4000) BN 0
J 0
(-3200 4010);
DISPLAY 0.617021 (-3200 4010);
PAINT PINK (-3200 4010);
FORCEPROP 2 LAST CDS_LIB mstr_standard
J 2
(-3200 4000);
DISPLAY 0.787234 (-3200 4000);
PAINT MONO (-3200 4000);
DISPLAY INVISIBLE (-3200 4000);
FORCEPROP 1 LAST BODY_TYPE PLUMBING
J 0
(-3200 3950);
DISPLAY 1.234043 (-3200 3950);
PAINT GREEN (-3200 3950);
DISPLAY INVISIBLE (-3200 3950);
FORCEPROP 1 LAST HDL_TAP TRUE
J 0
(-2875 3875);
DISPLAY 1.234043 (-2875 3875);
PAINT GREEN (-2875 3875);
DISPLAY INVISIBLE (-2875 3875);
FORCEPROP 1 LAST PATH I129
J 0
(-3200 4000);
DISPLAY 0.936170 (-3200 4000);
PAINT GREEN (-3200 4000);
DISPLAY INVISIBLE (-3200 4000);
FORCEADD TAP..6
R 2
(700 4600);
FORCEPROP 3 LASTPIN (650 4600) SIG_NAME M_K_DQS_DP<11>
J 0
(660 4610);
DISPLAY 0.659574 (660 4610);
PAINT MONO (660 4610);
DISPLAY INVISIBLE (660 4610);
FORCEPROP 1 LASTPIN (650 4600) BN 11
J 2
(700 4610);
DISPLAY 0.617021 (700 4610);
PAINT PINK (700 4610);
FORCEPROP 2 LAST CDS_LIB mstr_standard
J 0
(700 4600);
DISPLAY 0.787234 (700 4600);
PAINT MONO (700 4600);
DISPLAY INVISIBLE (700 4600);
FORCEPROP 1 LAST BODY_TYPE PLUMBING
J 2
(700 4550);
DISPLAY 1.234043 (700 4550);
PAINT GREEN (700 4550);
DISPLAY INVISIBLE (700 4550);
FORCEPROP 1 LAST HDL_TAP TRUE
J 2
(375 4475);
DISPLAY 1.234043 (375 4475);
PAINT GREEN (375 4475);
DISPLAY INVISIBLE (375 4475);
FORCEPROP 1 LAST PATH I13
J 2
(700 4600);
DISPLAY 0.936170 (700 4600);
PAINT GREEN (700 4600);
DISPLAY INVISIBLE (700 4600);
FORCEADD TAP..6
(-3200 3900);
FORCEPROP 3 LASTPIN (-3150 3900) SIG_NAME M_K_BA<1>
J 0
(-3140 3910);
DISPLAY 0.659574 (-3140 3910);
PAINT MONO (-3140 3910);
DISPLAY INVISIBLE (-3140 3910);
FORCEPROP 1 LASTPIN (-3150 3900) BN 1
J 0
(-3200 3910);
DISPLAY 0.617021 (-3200 3910);
PAINT PINK (-3200 3910);
FORCEPROP 2 LAST CDS_LIB mstr_standard
J 0
(-3200 3900);
DISPLAY 0.787234 (-3200 3900);
PAINT MONO (-3200 3900);
DISPLAY INVISIBLE (-3200 3900);
FORCEPROP 1 LAST BODY_TYPE PLUMBING
J 0
(-3200 3850);
DISPLAY 1.234043 (-3200 3850);
PAINT GREEN (-3200 3850);
DISPLAY INVISIBLE (-3200 3850);
FORCEPROP 1 LAST HDL_TAP TRUE
J 0
(-2875 3775);
DISPLAY 1.234043 (-2875 3775);
PAINT GREEN (-2875 3775);
DISPLAY INVISIBLE (-2875 3775);
FORCEPROP 1 LAST PATH I130
J 0
(-3200 3900);
DISPLAY 0.936170 (-3200 3900);
PAINT GREEN (-3200 3900);
DISPLAY INVISIBLE (-3200 3900);
FORCEADD OFFPAGE..1
(-3850 4900);
FORCEPROP 2 LAST $XR1 84 
J 0
(-4191 4900);
DISPLAY 0.638298 (-4191 4900);
PAINT MONO (-4191 4900);
FORCEPROP 2 LAST $XR0 60 
J 0
(-4101 4900);
DISPLAY 0.638298 (-4101 4900);
PAINT MONO (-4101 4900);
FORCEPROP 2 LAST CDS_LIB mstr_standard
J 0
(-3850 4900);
DISPLAY 0.787234 (-3850 4900);
PAINT MONO (-3850 4900);
DISPLAY INVISIBLE (-3850 4900);
FORCEPROP 1 LAST OFFPAGE TRUE
J 0
(-3525 4775);
DISPLAY 0.936170 (-3525 4775);
PAINT GREEN (-3525 4775);
DISPLAY INVISIBLE (-3525 4775);
FORCEPROP 1 LAST COMMENT_BODY TRUE
J 0
(-3725 4800);
DISPLAY 0.936170 (-3725 4800);
PAINT GREEN (-3725 4800);
DISPLAY INVISIBLE (-3725 4800);
FORCEPROP 2 LAST PATH I131
J 0
(-3800 4975);
DISPLAY 0.787234 (-3800 4975);
PAINT MONO (-3800 4975);
DISPLAY INVISIBLE (-3800 4975);
FORCEADD OFFPAGE..1
(-3850 3950);
FORCEPROP 2 LAST $XR1 84 
J 0
(-4191 3950);
DISPLAY 0.638298 (-4191 3950);
PAINT MONO (-4191 3950);
FORCEPROP 2 LAST $XR0 60 
J 0
(-4101 3950);
DISPLAY 0.638298 (-4101 3950);
PAINT MONO (-4101 3950);
FORCEPROP 2 LAST CDS_LIB mstr_standard
J 0
(-3850 3950);
DISPLAY 0.787234 (-3850 3950);
PAINT MONO (-3850 3950);
DISPLAY INVISIBLE (-3850 3950);
FORCEPROP 1 LAST OFFPAGE TRUE
J 0
(-3525 3825);
DISPLAY 0.936170 (-3525 3825);
PAINT GREEN (-3525 3825);
DISPLAY INVISIBLE (-3525 3825);
FORCEPROP 1 LAST COMMENT_BODY TRUE
J 0
(-3725 3850);
DISPLAY 0.936170 (-3725 3850);
PAINT GREEN (-3725 3850);
DISPLAY INVISIBLE (-3725 3850);
FORCEPROP 2 LAST PATH I132
J 0
(-3800 4025);
DISPLAY 0.787234 (-3800 4025);
PAINT MONO (-3800 4025);
DISPLAY INVISIBLE (-3800 4025);
FORCEADD TAP..6
(-3200 3850);
FORCEPROP 3 LASTPIN (-3150 3850) SIG_NAME M_K_BA<0>
J 0
(-3140 3860);
DISPLAY 0.659574 (-3140 3860);
PAINT MONO (-3140 3860);
DISPLAY INVISIBLE (-3140 3860);
FORCEPROP 1 LASTPIN (-3150 3850) BN 0
J 0
(-3200 3860);
DISPLAY 0.617021 (-3200 3860);
PAINT PINK (-3200 3860);
FORCEPROP 2 LAST CDS_LIB mstr_standard
J 0
(-3200 3850);
DISPLAY 0.787234 (-3200 3850);
PAINT MONO (-3200 3850);
DISPLAY INVISIBLE (-3200 3850);
FORCEPROP 1 LAST BODY_TYPE PLUMBING
J 0
(-3200 3800);
DISPLAY 1.234043 (-3200 3800);
PAINT GREEN (-3200 3800);
DISPLAY INVISIBLE (-3200 3800);
FORCEPROP 1 LAST HDL_TAP TRUE
J 0
(-2875 3725);
DISPLAY 1.234043 (-2875 3725);
PAINT GREEN (-2875 3725);
DISPLAY INVISIBLE (-2875 3725);
FORCEPROP 1 LAST PATH I133
J 0
(-3200 3850);
DISPLAY 0.936170 (-3200 3850);
PAINT GREEN (-3200 3850);
DISPLAY INVISIBLE (-3200 3850);
FORCEADD TAP..6
(-3200 3800);
FORCEPROP 3 LASTPIN (-3150 3800) SIG_NAME M_K_BG<1>
J 0
(-3140 3810);
DISPLAY 0.659574 (-3140 3810);
PAINT MONO (-3140 3810);
DISPLAY INVISIBLE (-3140 3810);
FORCEPROP 1 LASTPIN (-3150 3800) BN 1
J 0
(-3200 3810);
DISPLAY 0.617021 (-3200 3810);
PAINT PINK (-3200 3810);
FORCEPROP 2 LAST CDS_LIB mstr_standard
J 0
(-3200 3800);
DISPLAY 0.787234 (-3200 3800);
PAINT MONO (-3200 3800);
DISPLAY INVISIBLE (-3200 3800);
FORCEPROP 1 LAST BODY_TYPE PLUMBING
J 0
(-3200 3750);
DISPLAY 1.234043 (-3200 3750);
PAINT GREEN (-3200 3750);
DISPLAY INVISIBLE (-3200 3750);
FORCEPROP 1 LAST HDL_TAP TRUE
J 0
(-2875 3675);
DISPLAY 1.234043 (-2875 3675);
PAINT GREEN (-2875 3675);
DISPLAY INVISIBLE (-2875 3675);
FORCEPROP 1 LAST PATH I134
J 0
(-3200 3800);
DISPLAY 0.936170 (-3200 3800);
PAINT GREEN (-3200 3800);
DISPLAY INVISIBLE (-3200 3800);
FORCEADD TAP..6
(-3200 3750);
FORCEPROP 3 LASTPIN (-3150 3750) SIG_NAME M_K_BG<0>
J 0
(-3140 3760);
DISPLAY 0.659574 (-3140 3760);
PAINT MONO (-3140 3760);
DISPLAY INVISIBLE (-3140 3760);
FORCEPROP 1 LASTPIN (-3150 3750) BN 0
J 0
(-3200 3760);
DISPLAY 0.617021 (-3200 3760);
PAINT PINK (-3200 3760);
FORCEPROP 2 LAST CDS_LIB mstr_standard
J 0
(-3200 3750);
DISPLAY 0.787234 (-3200 3750);
PAINT MONO (-3200 3750);
DISPLAY INVISIBLE (-3200 3750);
FORCEPROP 1 LAST BODY_TYPE PLUMBING
J 0
(-3200 3700);
DISPLAY 1.234043 (-3200 3700);
PAINT GREEN (-3200 3700);
DISPLAY INVISIBLE (-3200 3700);
FORCEPROP 1 LAST HDL_TAP TRUE
J 0
(-2875 3625);
DISPLAY 1.234043 (-2875 3625);
PAINT GREEN (-2875 3625);
DISPLAY INVISIBLE (-2875 3625);
FORCEPROP 1 LAST PATH I135
J 0
(-3200 3750);
DISPLAY 0.936170 (-3200 3750);
PAINT GREEN (-3200 3750);
DISPLAY INVISIBLE (-3200 3750);
FORCEADD OFFPAGE..1
(-3850 3450);
FORCEPROP 2 LAST $XR1 84 
J 0
(-4191 3450);
DISPLAY 0.638298 (-4191 3450);
PAINT MONO (-4191 3450);
FORCEPROP 2 LAST $XR0 60 
J 0
(-4101 3450);
DISPLAY 0.638298 (-4101 3450);
PAINT MONO (-4101 3450);
FORCEPROP 2 LAST CDS_LIB mstr_standard
J 0
(-3850 3450);
DISPLAY 0.787234 (-3850 3450);
PAINT MONO (-3850 3450);
DISPLAY INVISIBLE (-3850 3450);
FORCEPROP 1 LAST OFFPAGE TRUE
J 0
(-3525 3325);
DISPLAY 0.936170 (-3525 3325);
PAINT GREEN (-3525 3325);
DISPLAY INVISIBLE (-3525 3325);
FORCEPROP 1 LAST COMMENT_BODY TRUE
J 0
(-3725 3350);
DISPLAY 0.936170 (-3725 3350);
PAINT GREEN (-3725 3350);
DISPLAY INVISIBLE (-3725 3350);
FORCEPROP 2 LAST PATH I136
J 0
(-3800 3525);
DISPLAY 0.787234 (-3800 3525);
PAINT MONO (-3800 3525);
DISPLAY INVISIBLE (-3800 3525);
FORCEADD OFFPAGE..1
(-3850 3850);
FORCEPROP 2 LAST $XR1 84 
J 0
(-4191 3850);
DISPLAY 0.638298 (-4191 3850);
PAINT MONO (-4191 3850);
FORCEPROP 2 LAST $XR0 60 
J 0
(-4101 3850);
DISPLAY 0.638298 (-4101 3850);
PAINT MONO (-4101 3850);
FORCEPROP 2 LAST CDS_LIB mstr_standard
J 0
(-3850 3850);
DISPLAY 0.787234 (-3850 3850);
PAINT MONO (-3850 3850);
DISPLAY INVISIBLE (-3850 3850);
FORCEPROP 1 LAST OFFPAGE TRUE
J 0
(-3525 3725);
DISPLAY 0.936170 (-3525 3725);
PAINT GREEN (-3525 3725);
DISPLAY INVISIBLE (-3525 3725);
FORCEPROP 1 LAST COMMENT_BODY TRUE
J 0
(-3725 3750);
DISPLAY 0.936170 (-3725 3750);
PAINT GREEN (-3725 3750);
DISPLAY INVISIBLE (-3725 3750);
FORCEPROP 2 LAST PATH I137
J 0
(-3800 3925);
DISPLAY 0.787234 (-3800 3925);
PAINT MONO (-3800 3925);
DISPLAY INVISIBLE (-3800 3925);
FORCEADD TAP..6
(-3200 2800);
FORCEPROP 3 LASTPIN (-3150 2800) SIG_NAME M_K_ECC<6>
J 0
(-3140 2810);
DISPLAY 0.659574 (-3140 2810);
PAINT MONO (-3140 2810);
DISPLAY INVISIBLE (-3140 2810);
FORCEPROP 1 LASTPIN (-3150 2800) BN 6
J 0
(-3200 2810);
DISPLAY 0.617021 (-3200 2810);
PAINT PINK (-3200 2810);
FORCEPROP 2 LAST CDS_LIB mstr_standard
J 0
(-3200 2800);
DISPLAY 0.787234 (-3200 2800);
PAINT MONO (-3200 2800);
DISPLAY INVISIBLE (-3200 2800);
FORCEPROP 1 LAST BODY_TYPE PLUMBING
J 0
(-3200 2750);
DISPLAY 1.234043 (-3200 2750);
PAINT GREEN (-3200 2750);
DISPLAY INVISIBLE (-3200 2750);
FORCEPROP 1 LAST HDL_TAP TRUE
J 0
(-2875 2675);
DISPLAY 1.234043 (-2875 2675);
PAINT GREEN (-2875 2675);
DISPLAY INVISIBLE (-2875 2675);
FORCEPROP 1 LAST PATH I138
J 0
(-3200 2800);
DISPLAY 0.936170 (-3200 2800);
PAINT GREEN (-3200 2800);
DISPLAY INVISIBLE (-3200 2800);
FORCEADD TAP..6
(-3200 2750);
FORCEPROP 3 LASTPIN (-3150 2750) SIG_NAME M_K_ECC<7>
J 0
(-3140 2760);
DISPLAY 0.659574 (-3140 2760);
PAINT MONO (-3140 2760);
DISPLAY INVISIBLE (-3140 2760);
FORCEPROP 1 LASTPIN (-3150 2750) BN 7
J 0
(-3200 2760);
DISPLAY 0.617021 (-3200 2760);
PAINT PINK (-3200 2760);
FORCEPROP 2 LAST CDS_LIB mstr_standard
J 0
(-3200 2750);
DISPLAY 0.787234 (-3200 2750);
PAINT MONO (-3200 2750);
DISPLAY INVISIBLE (-3200 2750);
FORCEPROP 1 LAST BODY_TYPE PLUMBING
J 0
(-3200 2700);
DISPLAY 1.234043 (-3200 2700);
PAINT GREEN (-3200 2700);
DISPLAY INVISIBLE (-3200 2700);
FORCEPROP 1 LAST HDL_TAP TRUE
J 0
(-2875 2625);
DISPLAY 1.234043 (-2875 2625);
PAINT GREEN (-2875 2625);
DISPLAY INVISIBLE (-2875 2625);
FORCEPROP 1 LAST PATH I139
J 0
(-3200 2750);
DISPLAY 0.936170 (-3200 2750);
PAINT GREEN (-3200 2750);
DISPLAY INVISIBLE (-3200 2750);
FORCEADD TAP..6
R 2
(700 4700);
FORCEPROP 3 LASTPIN (650 4700) SIG_NAME M_K_DQS_DP<12>
J 0
(660 4710);
DISPLAY 0.659574 (660 4710);
PAINT MONO (660 4710);
DISPLAY INVISIBLE (660 4710);
FORCEPROP 1 LASTPIN (650 4700) BN 12
J 2
(700 4710);
DISPLAY 0.617021 (700 4710);
PAINT PINK (700 4710);
FORCEPROP 2 LAST CDS_LIB mstr_standard
J 0
(700 4700);
DISPLAY 0.787234 (700 4700);
PAINT MONO (700 4700);
DISPLAY INVISIBLE (700 4700);
FORCEPROP 1 LAST BODY_TYPE PLUMBING
J 2
(700 4650);
DISPLAY 1.234043 (700 4650);
PAINT GREEN (700 4650);
DISPLAY INVISIBLE (700 4650);
FORCEPROP 1 LAST HDL_TAP TRUE
J 2
(375 4575);
DISPLAY 1.234043 (375 4575);
PAINT GREEN (375 4575);
DISPLAY INVISIBLE (375 4575);
FORCEPROP 1 LAST PATH I14
J 2
(700 4700);
DISPLAY 0.936170 (700 4700);
PAINT GREEN (700 4700);
DISPLAY INVISIBLE (700 4700);
FORCEADD TAP..6
(-3200 2700);
FORCEPROP 3 LASTPIN (-3150 2700) SIG_NAME M_K_ECC<4>
J 0
(-3140 2710);
DISPLAY 0.659574 (-3140 2710);
PAINT MONO (-3140 2710);
DISPLAY INVISIBLE (-3140 2710);
FORCEPROP 1 LASTPIN (-3150 2700) BN 4
J 0
(-3200 2710);
DISPLAY 0.617021 (-3200 2710);
PAINT PINK (-3200 2710);
FORCEPROP 2 LAST CDS_LIB mstr_standard
J 0
(-3200 2700);
DISPLAY 0.787234 (-3200 2700);
PAINT MONO (-3200 2700);
DISPLAY INVISIBLE (-3200 2700);
FORCEPROP 1 LAST BODY_TYPE PLUMBING
J 0
(-3200 2650);
DISPLAY 1.234043 (-3200 2650);
PAINT GREEN (-3200 2650);
DISPLAY INVISIBLE (-3200 2650);
FORCEPROP 1 LAST HDL_TAP TRUE
J 0
(-2875 2575);
DISPLAY 1.234043 (-2875 2575);
PAINT GREEN (-2875 2575);
DISPLAY INVISIBLE (-2875 2575);
FORCEPROP 1 LAST PATH I140
J 0
(-3200 2700);
DISPLAY 0.936170 (-3200 2700);
PAINT GREEN (-3200 2700);
DISPLAY INVISIBLE (-3200 2700);
FORCEADD TAP..6
(-3200 2650);
FORCEPROP 3 LASTPIN (-3150 2650) SIG_NAME M_K_ECC<5>
J 0
(-3140 2660);
DISPLAY 0.659574 (-3140 2660);
PAINT MONO (-3140 2660);
DISPLAY INVISIBLE (-3140 2660);
FORCEPROP 1 LASTPIN (-3150 2650) BN 5
J 0
(-3200 2660);
DISPLAY 0.617021 (-3200 2660);
PAINT PINK (-3200 2660);
FORCEPROP 2 LAST CDS_LIB mstr_standard
J 0
(-3200 2650);
DISPLAY 0.787234 (-3200 2650);
PAINT MONO (-3200 2650);
DISPLAY INVISIBLE (-3200 2650);
FORCEPROP 1 LAST BODY_TYPE PLUMBING
J 0
(-3200 2600);
DISPLAY 1.234043 (-3200 2600);
PAINT GREEN (-3200 2600);
DISPLAY INVISIBLE (-3200 2600);
FORCEPROP 1 LAST HDL_TAP TRUE
J 0
(-2875 2525);
DISPLAY 1.234043 (-2875 2525);
PAINT GREEN (-2875 2525);
DISPLAY INVISIBLE (-2875 2525);
FORCEPROP 1 LAST PATH I141
J 0
(-3200 2650);
DISPLAY 0.936170 (-3200 2650);
PAINT GREEN (-3200 2650);
DISPLAY INVISIBLE (-3200 2650);
FORCEADD TAP..6
(-3200 2600);
FORCEPROP 3 LASTPIN (-3150 2600) SIG_NAME M_K_ECC<2>
J 0
(-3140 2610);
DISPLAY 0.659574 (-3140 2610);
PAINT MONO (-3140 2610);
DISPLAY INVISIBLE (-3140 2610);
FORCEPROP 1 LASTPIN (-3150 2600) BN 2
J 0
(-3200 2610);
DISPLAY 0.617021 (-3200 2610);
PAINT PINK (-3200 2610);
FORCEPROP 2 LAST CDS_LIB mstr_standard
J 0
(-3200 2600);
DISPLAY 0.787234 (-3200 2600);
PAINT MONO (-3200 2600);
DISPLAY INVISIBLE (-3200 2600);
FORCEPROP 1 LAST BODY_TYPE PLUMBING
J 0
(-3200 2550);
DISPLAY 1.234043 (-3200 2550);
PAINT GREEN (-3200 2550);
DISPLAY INVISIBLE (-3200 2550);
FORCEPROP 1 LAST HDL_TAP TRUE
J 0
(-2875 2475);
DISPLAY 1.234043 (-2875 2475);
PAINT GREEN (-2875 2475);
DISPLAY INVISIBLE (-2875 2475);
FORCEPROP 1 LAST PATH I142
J 0
(-3200 2600);
DISPLAY 0.936170 (-3200 2600);
PAINT GREEN (-3200 2600);
DISPLAY INVISIBLE (-3200 2600);
FORCEADD TAP..6
(-3200 2550);
FORCEPROP 3 LASTPIN (-3150 2550) SIG_NAME M_K_ECC<3>
J 0
(-3140 2560);
DISPLAY 0.659574 (-3140 2560);
PAINT MONO (-3140 2560);
DISPLAY INVISIBLE (-3140 2560);
FORCEPROP 1 LASTPIN (-3150 2550) BN 3
J 0
(-3200 2560);
DISPLAY 0.617021 (-3200 2560);
PAINT PINK (-3200 2560);
FORCEPROP 2 LAST CDS_LIB mstr_standard
J 0
(-3200 2550);
DISPLAY 0.787234 (-3200 2550);
PAINT MONO (-3200 2550);
DISPLAY INVISIBLE (-3200 2550);
FORCEPROP 1 LAST BODY_TYPE PLUMBING
J 0
(-3200 2500);
DISPLAY 1.234043 (-3200 2500);
PAINT GREEN (-3200 2500);
DISPLAY INVISIBLE (-3200 2500);
FORCEPROP 1 LAST HDL_TAP TRUE
J 0
(-2875 2425);
DISPLAY 1.234043 (-2875 2425);
PAINT GREEN (-2875 2425);
DISPLAY INVISIBLE (-2875 2425);
FORCEPROP 1 LAST PATH I143
J 0
(-3200 2550);
DISPLAY 0.936170 (-3200 2550);
PAINT GREEN (-3200 2550);
DISPLAY INVISIBLE (-3200 2550);
FORCEADD TAP..6
(-3200 2500);
FORCEPROP 3 LASTPIN (-3150 2500) SIG_NAME M_K_ECC<0>
J 0
(-3140 2510);
DISPLAY 0.659574 (-3140 2510);
PAINT MONO (-3140 2510);
DISPLAY INVISIBLE (-3140 2510);
FORCEPROP 1 LASTPIN (-3150 2500) BN 0
J 0
(-3200 2510);
DISPLAY 0.617021 (-3200 2510);
PAINT PINK (-3200 2510);
FORCEPROP 2 LAST CDS_LIB mstr_standard
J 0
(-3200 2500);
DISPLAY 0.787234 (-3200 2500);
PAINT MONO (-3200 2500);
DISPLAY INVISIBLE (-3200 2500);
FORCEPROP 1 LAST BODY_TYPE PLUMBING
J 0
(-3200 2450);
DISPLAY 1.234043 (-3200 2450);
PAINT GREEN (-3200 2450);
DISPLAY INVISIBLE (-3200 2450);
FORCEPROP 1 LAST HDL_TAP TRUE
J 0
(-2875 2375);
DISPLAY 1.234043 (-2875 2375);
PAINT GREEN (-2875 2375);
DISPLAY INVISIBLE (-2875 2375);
FORCEPROP 1 LAST PATH I144
J 0
(-3200 2500);
DISPLAY 0.936170 (-3200 2500);
PAINT GREEN (-3200 2500);
DISPLAY INVISIBLE (-3200 2500);
FORCEADD TAP..6
(-3200 2450);
FORCEPROP 3 LASTPIN (-3150 2450) SIG_NAME M_K_ECC<1>
J 0
(-3140 2460);
DISPLAY 0.659574 (-3140 2460);
PAINT MONO (-3140 2460);
DISPLAY INVISIBLE (-3140 2460);
FORCEPROP 1 LASTPIN (-3150 2450) BN 1
J 0
(-3200 2460);
DISPLAY 0.617021 (-3200 2460);
PAINT PINK (-3200 2460);
FORCEPROP 2 LAST CDS_LIB mstr_standard
J 0
(-3200 2450);
DISPLAY 0.787234 (-3200 2450);
PAINT MONO (-3200 2450);
DISPLAY INVISIBLE (-3200 2450);
FORCEPROP 1 LAST BODY_TYPE PLUMBING
J 0
(-3200 2400);
DISPLAY 1.234043 (-3200 2400);
PAINT GREEN (-3200 2400);
DISPLAY INVISIBLE (-3200 2400);
FORCEPROP 1 LAST HDL_TAP TRUE
J 0
(-2875 2325);
DISPLAY 1.234043 (-2875 2325);
PAINT GREEN (-2875 2325);
DISPLAY INVISIBLE (-2875 2325);
FORCEPROP 1 LAST PATH I145
J 0
(-3200 2450);
DISPLAY 0.936170 (-3200 2450);
PAINT GREEN (-3200 2450);
DISPLAY INVISIBLE (-3200 2450);
FORCEADD OFFPAGE..1
(-3850 2800);
FORCEPROP 2 LAST $XR1 84 
J 0
(-4191 2800);
DISPLAY 0.638298 (-4191 2800);
PAINT MONO (-4191 2800);
FORCEPROP 2 LAST $XR0 60 
J 0
(-4101 2800);
DISPLAY 0.638298 (-4101 2800);
PAINT MONO (-4101 2800);
FORCEPROP 2 LAST CDS_LIB mstr_standard
J 0
(-3850 2800);
DISPLAY 0.787234 (-3850 2800);
PAINT MONO (-3850 2800);
DISPLAY INVISIBLE (-3850 2800);
FORCEPROP 1 LAST OFFPAGE TRUE
J 0
(-3525 2675);
DISPLAY 0.936170 (-3525 2675);
PAINT GREEN (-3525 2675);
DISPLAY INVISIBLE (-3525 2675);
FORCEPROP 1 LAST COMMENT_BODY TRUE
J 0
(-3725 2700);
DISPLAY 0.936170 (-3725 2700);
PAINT GREEN (-3725 2700);
DISPLAY INVISIBLE (-3725 2700);
FORCEPROP 2 LAST PATH I146
J 0
(-3800 2875);
DISPLAY 0.787234 (-3800 2875);
PAINT MONO (-3800 2875);
DISPLAY INVISIBLE (-3800 2875);
FORCEADD OFFPAGE..1
(-4000 2150);
FORCEPROP 2 LAST $XR1 84 
J 0
(-4341 2150);
DISPLAY 0.638298 (-4341 2150);
PAINT MONO (-4341 2150);
FORCEPROP 2 LAST $XR0 60 
J 0
(-4251 2150);
DISPLAY 0.638298 (-4251 2150);
PAINT MONO (-4251 2150);
FORCEPROP 2 LAST CDS_LIB mstr_standard
J 0
(-4000 2150);
DISPLAY 0.787234 (-4000 2150);
PAINT MONO (-4000 2150);
DISPLAY INVISIBLE (-4000 2150);
FORCEPROP 1 LAST OFFPAGE TRUE
J 0
(-3675 2025);
DISPLAY 0.936170 (-3675 2025);
PAINT GREEN (-3675 2025);
DISPLAY INVISIBLE (-3675 2025);
FORCEPROP 1 LAST COMMENT_BODY TRUE
J 0
(-3875 2050);
DISPLAY 0.936170 (-3875 2050);
PAINT GREEN (-3875 2050);
DISPLAY INVISIBLE (-3875 2050);
FORCEPROP 2 LAST PATH I147
J 0
(-3950 2225);
DISPLAY 0.787234 (-3950 2225);
PAINT MONO (-3950 2225);
DISPLAY INVISIBLE (-3950 2225);
FORCEADD OFFPAGE..5
(-4025 2200);
FORCEPROP 2 LAST $XR1 60 
J 0
(-4339 2200);
DISPLAY 0.638298 (-4339 2200);
PAINT MONO (-4339 2200);
FORCEPROP 2 LAST $XR0 84 
J 0
(-4249 2200);
DISPLAY 0.638298 (-4249 2200);
PAINT MONO (-4249 2200);
FORCEPROP 2 LAST CDS_LIB mstr_standard
J 0
(-4025 2200);
DISPLAY 0.787234 (-4025 2200);
PAINT MONO (-4025 2200);
DISPLAY INVISIBLE (-4025 2200);
FORCEPROP 1 LAST OFFPAGE TRUE
J 0
(-3700 2075);
DISPLAY 1.404255 (-3700 2075);
PAINT GREEN (-3700 2075);
DISPLAY INVISIBLE (-3700 2075);
FORCEPROP 1 LAST COMMENT_BODY TRUE
J 0
(-3925 2125);
DISPLAY 1.404255 (-3925 2125);
PAINT GREEN (-3925 2125);
DISPLAY INVISIBLE (-3925 2125);
FORCEPROP 2 LAST PATH I148
J 0
(-3975 2275);
DISPLAY 0.787234 (-3975 2275);
PAINT MONO (-3975 2275);
DISPLAY INVISIBLE (-3975 2275);
FORCEADD OFFPAGE..1
(-3850 2750);
FORCEPROP 2 LAST $XR5 88 
J 0
(-4551 2750);
DISPLAY 0.638298 (-4551 2750);
PAINT MONO (-4551 2750);
FORCEPROP 2 LAST $XR4 87 
J 0
(-4461 2750);
DISPLAY 0.638298 (-4461 2750);
PAINT MONO (-4461 2750);
FORCEPROP 2 LAST $XR3 86 
J 0
(-4371 2750);
DISPLAY 0.638298 (-4371 2750);
PAINT MONO (-4371 2750);
FORCEPROP 2 LAST $XR2 85 
J 0
(-4281 2750);
DISPLAY 0.638298 (-4281 2750);
PAINT MONO (-4281 2750);
FORCEPROP 2 LAST $XR1 84 
J 0
(-4191 2750);
DISPLAY 0.638298 (-4191 2750);
PAINT MONO (-4191 2750);
FORCEPROP 2 LAST $XR0 55 
J 0
(-4101 2750);
DISPLAY 0.638298 (-4101 2750);
PAINT MONO (-4101 2750);
FORCEPROP 2 LAST CDS_LIB mstr_standard
J 0
(-3850 2750);
DISPLAY 0.787234 (-3850 2750);
PAINT MONO (-3850 2750);
DISPLAY INVISIBLE (-3850 2750);
FORCEPROP 1 LAST OFFPAGE TRUE
J 0
(-3525 2625);
DISPLAY 0.936170 (-3525 2625);
PAINT GREEN (-3525 2625);
DISPLAY INVISIBLE (-3525 2625);
FORCEPROP 1 LAST COMMENT_BODY TRUE
J 0
(-3725 2650);
DISPLAY 0.936170 (-3725 2650);
PAINT GREEN (-3725 2650);
DISPLAY INVISIBLE (-3725 2650);
FORCEPROP 2 LAST PATH I149
J 0
(-3800 2825);
DISPLAY 0.787234 (-3800 2825);
PAINT MONO (-3800 2825);
DISPLAY INVISIBLE (-3800 2825);
FORCEADD TAP..6
R 2
(700 4800);
FORCEPROP 3 LASTPIN (650 4800) SIG_NAME M_K_DQS_DP<13>
J 0
(660 4810);
DISPLAY 0.659574 (660 4810);
PAINT MONO (660 4810);
DISPLAY INVISIBLE (660 4810);
FORCEPROP 1 LASTPIN (650 4800) BN 13
J 2
(700 4810);
DISPLAY 0.617021 (700 4810);
PAINT PINK (700 4810);
FORCEPROP 2 LAST CDS_LIB mstr_standard
J 0
(700 4800);
DISPLAY 0.787234 (700 4800);
PAINT MONO (700 4800);
DISPLAY INVISIBLE (700 4800);
FORCEPROP 1 LAST BODY_TYPE PLUMBING
J 2
(700 4750);
DISPLAY 1.234043 (700 4750);
PAINT GREEN (700 4750);
DISPLAY INVISIBLE (700 4750);
FORCEPROP 1 LAST HDL_TAP TRUE
J 2
(375 4675);
DISPLAY 1.234043 (375 4675);
PAINT GREEN (375 4675);
DISPLAY INVISIBLE (375 4675);
FORCEPROP 1 LAST PATH I15
J 2
(700 4800);
DISPLAY 0.936170 (700 4800);
PAINT GREEN (700 4800);
DISPLAY INVISIBLE (700 4800);
FORCEADD OFFPAGE..6
(-3850 2850);
FORCEPROP 2 LAST $XR1 84 
J 0
(-4189 2850);
DISPLAY 0.638298 (-4189 2850);
PAINT MONO (-4189 2850);
FORCEPROP 2 LAST $XR0 60 
J 0
(-4099 2850);
DISPLAY 0.638298 (-4099 2850);
PAINT MONO (-4099 2850);
FORCEPROP 2 LAST CDS_LIB mstr_standard
J 0
(-3850 2850);
DISPLAY 0.787234 (-3850 2850);
PAINT MONO (-3850 2850);
DISPLAY INVISIBLE (-3850 2850);
FORCEPROP 1 LAST OFFPAGE TRUE
J 0
(-3525 2725);
DISPLAY 0.936170 (-3525 2725);
PAINT GREEN (-3525 2725);
DISPLAY INVISIBLE (-3525 2725);
FORCEPROP 1 LAST COMMENT_BODY TRUE
J 0
(-3750 2775);
DISPLAY 0.936170 (-3750 2775);
PAINT GREEN (-3750 2775);
DISPLAY INVISIBLE (-3750 2775);
FORCEPROP 2 LAST PATH I150
J 0
(-3800 2925);
DISPLAY 0.787234 (-3800 2925);
PAINT MONO (-3800 2925);
DISPLAY INVISIBLE (-3800 2925);
FORCEADD TAP..6
(-3200 3350);
FORCEPROP 3 LASTPIN (-3150 3350) SIG_NAME M_K_CS_N<3>
J 0
(-3140 3360);
DISPLAY 0.659574 (-3140 3360);
PAINT MONO (-3140 3360);
DISPLAY INVISIBLE (-3140 3360);
FORCEPROP 1 LASTPIN (-3150 3350) BN 3
J 0
(-3200 3360);
DISPLAY 0.617021 (-3200 3360);
PAINT PINK (-3200 3360);
FORCEPROP 2 LAST CDS_LIB mstr_standard
J 0
(-3200 3350);
DISPLAY 0.787234 (-3200 3350);
PAINT MONO (-3200 3350);
DISPLAY INVISIBLE (-3200 3350);
FORCEPROP 1 LAST BODY_TYPE PLUMBING
J 0
(-3200 3300);
DISPLAY 1.234043 (-3200 3300);
PAINT GREEN (-3200 3300);
DISPLAY INVISIBLE (-3200 3300);
FORCEPROP 1 LAST HDL_TAP TRUE
J 0
(-2875 3225);
DISPLAY 1.234043 (-2875 3225);
PAINT GREEN (-2875 3225);
DISPLAY INVISIBLE (-2875 3225);
FORCEPROP 1 LAST PATH I152
J 0
(-3200 3350);
DISPLAY 0.936170 (-3200 3350);
PAINT GREEN (-3200 3350);
DISPLAY INVISIBLE (-3200 3350);
FORCEADD TAP..6
(-3200 3300);
FORCEPROP 3 LASTPIN (-3150 3300) SIG_NAME M_K_CS_N<2>
J 0
(-3140 3310);
DISPLAY 0.659574 (-3140 3310);
PAINT MONO (-3140 3310);
DISPLAY INVISIBLE (-3140 3310);
FORCEPROP 1 LASTPIN (-3150 3300) BN 2
J 0
(-3200 3310);
DISPLAY 0.617021 (-3200 3310);
PAINT PINK (-3200 3310);
FORCEPROP 2 LAST CDS_LIB mstr_standard
J 0
(-3200 3300);
DISPLAY 0.787234 (-3200 3300);
PAINT MONO (-3200 3300);
DISPLAY INVISIBLE (-3200 3300);
FORCEPROP 1 LAST BODY_TYPE PLUMBING
J 0
(-3200 3250);
DISPLAY 1.234043 (-3200 3250);
PAINT GREEN (-3200 3250);
DISPLAY INVISIBLE (-3200 3250);
FORCEPROP 1 LAST HDL_TAP TRUE
J 0
(-2875 3175);
DISPLAY 1.234043 (-2875 3175);
PAINT GREEN (-2875 3175);
DISPLAY INVISIBLE (-2875 3175);
FORCEPROP 1 LAST PATH I153
J 0
(-3200 3300);
DISPLAY 0.936170 (-3200 3300);
PAINT GREEN (-3200 3300);
DISPLAY INVISIBLE (-3200 3300);
FORCEADD TAP..6
(-3200 3050);
FORCEPROP 3 LASTPIN (-3150 3050) SIG_NAME M_K_CKE<0>
J 0
(-3140 3060);
DISPLAY 0.659574 (-3140 3060);
PAINT MONO (-3140 3060);
DISPLAY INVISIBLE (-3140 3060);
FORCEPROP 1 LASTPIN (-3150 3050) BN 0
J 0
(-3200 3060);
DISPLAY 0.617021 (-3200 3060);
PAINT PINK (-3200 3060);
FORCEPROP 2 LAST CDS_LIB mstr_standard
J 0
(-3200 3050);
DISPLAY 0.787234 (-3200 3050);
PAINT MONO (-3200 3050);
DISPLAY INVISIBLE (-3200 3050);
FORCEPROP 1 LAST BODY_TYPE PLUMBING
J 0
(-3200 3000);
DISPLAY 1.234043 (-3200 3000);
PAINT GREEN (-3200 3000);
DISPLAY INVISIBLE (-3200 3000);
FORCEPROP 1 LAST HDL_TAP TRUE
J 0
(-2875 2925);
DISPLAY 1.234043 (-2875 2925);
PAINT GREEN (-2875 2925);
DISPLAY INVISIBLE (-2875 2925);
FORCEPROP 1 LAST PATH I154
J 0
(-3200 3050);
DISPLAY 0.936170 (-3200 3050);
PAINT GREEN (-3200 3050);
DISPLAY INVISIBLE (-3200 3050);
FORCEADD TAP..6
(-3200 2900);
FORCEPROP 3 LASTPIN (-3150 2900) SIG_NAME M_K_ODT<0>
J 0
(-3140 2910);
DISPLAY 0.659574 (-3140 2910);
PAINT MONO (-3140 2910);
DISPLAY INVISIBLE (-3140 2910);
FORCEPROP 1 LASTPIN (-3150 2900) BN 0
J 0
(-3200 2910);
DISPLAY 0.617021 (-3200 2910);
PAINT PINK (-3200 2910);
FORCEPROP 2 LAST CDS_LIB mstr_standard
J 0
(-3200 2900);
DISPLAY 0.787234 (-3200 2900);
PAINT MONO (-3200 2900);
DISPLAY INVISIBLE (-3200 2900);
FORCEPROP 1 LAST BODY_TYPE PLUMBING
J 0
(-3200 2850);
DISPLAY 1.234043 (-3200 2850);
PAINT GREEN (-3200 2850);
DISPLAY INVISIBLE (-3200 2850);
FORCEPROP 1 LAST HDL_TAP TRUE
J 0
(-2875 2775);
DISPLAY 1.234043 (-2875 2775);
PAINT GREEN (-2875 2775);
DISPLAY INVISIBLE (-2875 2775);
FORCEPROP 1 LAST PATH I155
J 0
(-3200 2900);
DISPLAY 0.936170 (-3200 2900);
PAINT GREEN (-3200 2900);
DISPLAY INVISIBLE (-3200 2900);
FORCEADD TAP..6
(-3550 3550);
FORCEPROP 3 LASTPIN (-3500 3550) SIG_NAME M_K_CLK_DP<0>
J 0
(-3490 3560);
DISPLAY 0.659574 (-3490 3560);
PAINT MONO (-3490 3560);
DISPLAY INVISIBLE (-3490 3560);
FORCEPROP 1 LASTPIN (-3500 3550) BN 0
J 0
(-3550 3560);
DISPLAY 0.617021 (-3550 3560);
PAINT PINK (-3550 3560);
FORCEPROP 2 LAST CDS_LIB mstr_standard
J 0
(-3550 3550);
DISPLAY 0.787234 (-3550 3550);
PAINT MONO (-3550 3550);
DISPLAY INVISIBLE (-3550 3550);
FORCEPROP 1 LAST BODY_TYPE PLUMBING
J 0
(-3550 3500);
DISPLAY 1.234043 (-3550 3500);
PAINT GREEN (-3550 3500);
DISPLAY INVISIBLE (-3550 3500);
FORCEPROP 1 LAST HDL_TAP TRUE
J 0
(-3225 3425);
DISPLAY 1.234043 (-3225 3425);
PAINT GREEN (-3225 3425);
DISPLAY INVISIBLE (-3225 3425);
FORCEPROP 1 LAST PATH I156
J 0
(-3550 3550);
DISPLAY 0.936170 (-3550 3550);
PAINT GREEN (-3550 3550);
DISPLAY INVISIBLE (-3550 3550);
FORCEADD OFFPAGE..1
(-4250 3700);
FORCEPROP 2 LAST $XR1 84 
J 0
(-4591 3700);
DISPLAY 0.638298 (-4591 3700);
PAINT MONO (-4591 3700);
FORCEPROP 2 LAST $XR0 60 
J 0
(-4501 3700);
DISPLAY 0.638298 (-4501 3700);
PAINT MONO (-4501 3700);
FORCEPROP 2 LAST CDS_LIB mstr_standard
J 0
(-4250 3700);
DISPLAY 0.787234 (-4250 3700);
PAINT MONO (-4250 3700);
DISPLAY INVISIBLE (-4250 3700);
FORCEPROP 1 LAST OFFPAGE TRUE
J 0
(-3925 3575);
DISPLAY 0.936170 (-3925 3575);
PAINT GREEN (-3925 3575);
DISPLAY INVISIBLE (-3925 3575);
FORCEPROP 1 LAST COMMENT_BODY TRUE
J 0
(-4125 3600);
DISPLAY 0.936170 (-4125 3600);
PAINT GREEN (-4125 3600);
DISPLAY INVISIBLE (-4125 3600);
FORCEPROP 2 LAST PATH I157
J 0
(-4200 3775);
DISPLAY 0.787234 (-4200 3775);
PAINT MONO (-4200 3775);
DISPLAY INVISIBLE (-4200 3775);
FORCEADD OFFPAGE..1
(-4250 3750);
FORCEPROP 2 LAST $XR1 84 
J 0
(-4591 3750);
DISPLAY 0.638298 (-4591 3750);
PAINT MONO (-4591 3750);
FORCEPROP 2 LAST $XR0 60 
J 0
(-4501 3750);
DISPLAY 0.638298 (-4501 3750);
PAINT MONO (-4501 3750);
FORCEPROP 2 LAST CDS_LIB mstr_standard
J 0
(-4250 3750);
DISPLAY 0.787234 (-4250 3750);
PAINT MONO (-4250 3750);
DISPLAY INVISIBLE (-4250 3750);
FORCEPROP 1 LAST OFFPAGE TRUE
J 0
(-3925 3625);
DISPLAY 0.936170 (-3925 3625);
PAINT GREEN (-3925 3625);
DISPLAY INVISIBLE (-3925 3625);
FORCEPROP 1 LAST COMMENT_BODY TRUE
J 0
(-4125 3650);
DISPLAY 0.936170 (-4125 3650);
PAINT GREEN (-4125 3650);
DISPLAY INVISIBLE (-4125 3650);
FORCEPROP 2 LAST PATH I158
J 0
(-4200 3825);
DISPLAY 0.787234 (-4200 3825);
PAINT MONO (-4200 3825);
DISPLAY INVISIBLE (-4200 3825);
FORCEADD TAP..6
(-3700 3500);
FORCEPROP 3 LASTPIN (-3650 3500) SIG_NAME M_K_CLK_DN<0>
J 0
(-3640 3510);
DISPLAY 0.659574 (-3640 3510);
PAINT MONO (-3640 3510);
DISPLAY INVISIBLE (-3640 3510);
FORCEPROP 1 LASTPIN (-3650 3500) BN 0
J 0
(-3700 3510);
DISPLAY 0.617021 (-3700 3510);
PAINT PINK (-3700 3510);
FORCEPROP 2 LAST CDS_LIB mstr_standard
J 0
(-3700 3500);
DISPLAY 0.787234 (-3700 3500);
PAINT MONO (-3700 3500);
DISPLAY INVISIBLE (-3700 3500);
FORCEPROP 1 LAST BODY_TYPE PLUMBING
J 0
(-3700 3450);
DISPLAY 1.234043 (-3700 3450);
PAINT GREEN (-3700 3450);
DISPLAY INVISIBLE (-3700 3450);
FORCEPROP 1 LAST HDL_TAP TRUE
J 0
(-3375 3375);
DISPLAY 1.234043 (-3375 3375);
PAINT GREEN (-3375 3375);
DISPLAY INVISIBLE (-3375 3375);
FORCEPROP 1 LAST PATH I159
J 0
(-3700 3500);
DISPLAY 0.936170 (-3700 3500);
PAINT GREEN (-3700 3500);
DISPLAY INVISIBLE (-3700 3500);
FORCEADD PVDDQ_KLM..1
(-1300 2625);
FORCEPROP 3 LASTPIN (-1300 2575) SIG_NAME PVDDQ_KLM\g
J 0
(-1290 2585);
DISPLAY 0.659574 (-1290 2585);
PAINT MONO (-1290 2585);
DISPLAY INVISIBLE (-1290 2585);
FORCEPROP 1 LAST VOLTAGE 1.2V
J 0
(-1345 2582);
DISPLAY 0.340426 (-1345 2582);
PAINT SKYBLUE (-1345 2582);
DISPLAY INVISIBLE (-1345 2582);
FORCEPROP 2 LAST BOM_COST MEM
J 0
(-1300 2630);
PAINT ORANGE (-1300 2630);
DISPLAY INVISIBLE (-1300 2630);
FORCEPROP 2 LAST CDS_LIB mstr_symbols
J 0
(-1300 2625);
PAINT ORANGE (-1300 2625);
DISPLAY INVISIBLE (-1300 2625);
FORCEPROP 1 LAST BODY_TYPE PLUMBING
J 0
(-1345 2582);
DISPLAY 0.340426 (-1345 2582);
PAINT GREEN (-1345 2582);
DISPLAY INVISIBLE (-1345 2582);
FORCEPROP 1 LAST PATH I16
J 0
(-1250 2650);
DISPLAY 0.872340 (-1250 2650);
PAINT AQUA (-1250 2650);
DISPLAY INVISIBLE (-1250 2650);
FORCEPROP 2 LAST ROOM DDR4_CH_C
J 0
(-1300 2725);
DISPLAY 0.787234 (-1300 2725);
PAINT ORANGE (-1300 2725);
DISPLAY INVISIBLE (-1300 2725);
FORCEPROP 1 LAST HDL_POWER PVDDQ_KLM
J 1
(-1300 2675);
DISPLAY 0.872340 (-1300 2675);
PAINT GREEN (-1300 2675);
DISPLAY INVISIBLE (-1300 2675);
FORCEADD OFFPAGE..1
(-3850 3400);
FORCEPROP 2 LAST $XR1 84 
J 0
(-4191 3400);
DISPLAY 0.638298 (-4191 3400);
PAINT MONO (-4191 3400);
FORCEPROP 2 LAST $XR0 60 
J 0
(-4101 3400);
DISPLAY 0.638298 (-4101 3400);
PAINT MONO (-4101 3400);
FORCEPROP 2 LAST CDS_LIB mstr_standard
J 0
(-3850 3400);
DISPLAY 0.787234 (-3850 3400);
PAINT MONO (-3850 3400);
DISPLAY INVISIBLE (-3850 3400);
FORCEPROP 1 LAST OFFPAGE TRUE
J 0
(-3525 3275);
DISPLAY 0.936170 (-3525 3275);
PAINT GREEN (-3525 3275);
DISPLAY INVISIBLE (-3525 3275);
FORCEPROP 1 LAST COMMENT_BODY TRUE
J 0
(-3725 3300);
DISPLAY 0.936170 (-3725 3300);
PAINT GREEN (-3725 3300);
DISPLAY INVISIBLE (-3725 3300);
FORCEPROP 2 LAST PATH I160
J 0
(-3800 3475);
DISPLAY 0.787234 (-3800 3475);
PAINT MONO (-3800 3475);
DISPLAY INVISIBLE (-3800 3475);
FORCEADD OFFPAGE..1
(-3850 3000);
FORCEPROP 2 LAST $XR1 84 
J 0
(-4191 3000);
DISPLAY 0.638298 (-4191 3000);
PAINT MONO (-4191 3000);
FORCEPROP 2 LAST $XR0 60 
J 0
(-4101 3000);
DISPLAY 0.638298 (-4101 3000);
PAINT MONO (-4101 3000);
FORCEPROP 2 LAST CDS_LIB mstr_standard
J 0
(-3850 3000);
DISPLAY 0.787234 (-3850 3000);
PAINT MONO (-3850 3000);
DISPLAY INVISIBLE (-3850 3000);
FORCEPROP 1 LAST OFFPAGE TRUE
J 0
(-3525 2875);
DISPLAY 0.936170 (-3525 2875);
PAINT GREEN (-3525 2875);
DISPLAY INVISIBLE (-3525 2875);
FORCEPROP 1 LAST COMMENT_BODY TRUE
J 0
(-3725 2900);
DISPLAY 0.936170 (-3725 2900);
PAINT GREEN (-3725 2900);
DISPLAY INVISIBLE (-3725 2900);
FORCEPROP 2 LAST PATH I161
J 0
(-3800 3075);
DISPLAY 0.787234 (-3800 3075);
PAINT MONO (-3800 3075);
DISPLAY INVISIBLE (-3800 3075);
FORCEADD OFFPAGE..1
(-3850 3150);
FORCEPROP 2 LAST $XR1 84 
J 0
(-4191 3150);
DISPLAY 0.638298 (-4191 3150);
PAINT MONO (-4191 3150);
FORCEPROP 2 LAST $XR0 60 
J 0
(-4101 3150);
DISPLAY 0.638298 (-4101 3150);
PAINT MONO (-4101 3150);
FORCEPROP 2 LAST CDS_LIB mstr_standard
J 0
(-3850 3150);
DISPLAY 0.787234 (-3850 3150);
PAINT MONO (-3850 3150);
DISPLAY INVISIBLE (-3850 3150);
FORCEPROP 1 LAST OFFPAGE TRUE
J 0
(-3525 3025);
DISPLAY 0.936170 (-3525 3025);
PAINT GREEN (-3525 3025);
DISPLAY INVISIBLE (-3525 3025);
FORCEPROP 1 LAST COMMENT_BODY TRUE
J 0
(-3725 3050);
DISPLAY 0.936170 (-3725 3050);
PAINT GREEN (-3725 3050);
DISPLAY INVISIBLE (-3725 3050);
FORCEPROP 2 LAST PATH I162
J 0
(-3800 3225);
DISPLAY 0.787234 (-3800 3225);
PAINT MONO (-3800 3225);
DISPLAY INVISIBLE (-3800 3225);
FORCEADD TAP..6
(-3200 3250);
FORCEPROP 3 LASTPIN (-3150 3250) SIG_NAME M_K_CS_N<1>
J 0
(-3140 3260);
DISPLAY 0.659574 (-3140 3260);
PAINT MONO (-3140 3260);
DISPLAY INVISIBLE (-3140 3260);
FORCEPROP 1 LASTPIN (-3150 3250) BN 1
J 0
(-3200 3260);
DISPLAY 0.617021 (-3200 3260);
PAINT PINK (-3200 3260);
FORCEPROP 2 LAST CDS_LIB mstr_standard
J 0
(-3200 3250);
DISPLAY 0.787234 (-3200 3250);
PAINT MONO (-3200 3250);
DISPLAY INVISIBLE (-3200 3250);
FORCEPROP 1 LAST BODY_TYPE PLUMBING
J 0
(-3200 3200);
DISPLAY 1.234043 (-3200 3200);
PAINT GREEN (-3200 3200);
DISPLAY INVISIBLE (-3200 3200);
FORCEPROP 1 LAST HDL_TAP TRUE
J 0
(-2875 3125);
DISPLAY 1.234043 (-2875 3125);
PAINT GREEN (-2875 3125);
DISPLAY INVISIBLE (-2875 3125);
FORCEPROP 1 LAST PATH I163
J 0
(-3200 3250);
DISPLAY 0.936170 (-3200 3250);
PAINT GREEN (-3200 3250);
DISPLAY INVISIBLE (-3200 3250);
FORCEADD TAP..6
(-3200 3200);
FORCEPROP 3 LASTPIN (-3150 3200) SIG_NAME M_K_CS_N<0>
J 0
(-3140 3210);
DISPLAY 0.659574 (-3140 3210);
PAINT MONO (-3140 3210);
DISPLAY INVISIBLE (-3140 3210);
FORCEPROP 1 LASTPIN (-3150 3200) BN 0
J 0
(-3200 3210);
DISPLAY 0.617021 (-3200 3210);
PAINT PINK (-3200 3210);
FORCEPROP 2 LAST CDS_LIB mstr_standard
J 0
(-3200 3200);
DISPLAY 0.787234 (-3200 3200);
PAINT MONO (-3200 3200);
DISPLAY INVISIBLE (-3200 3200);
FORCEPROP 1 LAST BODY_TYPE PLUMBING
J 0
(-3200 3150);
DISPLAY 1.234043 (-3200 3150);
PAINT GREEN (-3200 3150);
DISPLAY INVISIBLE (-3200 3150);
FORCEPROP 1 LAST HDL_TAP TRUE
J 0
(-2875 3075);
DISPLAY 1.234043 (-2875 3075);
PAINT GREEN (-2875 3075);
DISPLAY INVISIBLE (-2875 3075);
FORCEPROP 1 LAST PATH I164
J 0
(-3200 3200);
DISPLAY 0.936170 (-3200 3200);
PAINT GREEN (-3200 3200);
DISPLAY INVISIBLE (-3200 3200);
FORCEADD TAP..6
(-3200 3100);
FORCEPROP 3 LASTPIN (-3150 3100) SIG_NAME M_K_CKE<1>
J 0
(-3140 3110);
DISPLAY 0.659574 (-3140 3110);
PAINT MONO (-3140 3110);
DISPLAY INVISIBLE (-3140 3110);
FORCEPROP 1 LASTPIN (-3150 3100) BN 1
J 0
(-3200 3110);
DISPLAY 0.617021 (-3200 3110);
PAINT PINK (-3200 3110);
FORCEPROP 2 LAST CDS_LIB mstr_standard
J 0
(-3200 3100);
DISPLAY 0.787234 (-3200 3100);
PAINT MONO (-3200 3100);
DISPLAY INVISIBLE (-3200 3100);
FORCEPROP 1 LAST BODY_TYPE PLUMBING
J 0
(-3200 3050);
DISPLAY 1.234043 (-3200 3050);
PAINT GREEN (-3200 3050);
DISPLAY INVISIBLE (-3200 3050);
FORCEPROP 1 LAST HDL_TAP TRUE
J 0
(-2875 2975);
DISPLAY 1.234043 (-2875 2975);
PAINT GREEN (-2875 2975);
DISPLAY INVISIBLE (-2875 2975);
FORCEPROP 1 LAST PATH I165
J 0
(-3200 3100);
DISPLAY 0.936170 (-3200 3100);
PAINT GREEN (-3200 3100);
DISPLAY INVISIBLE (-3200 3100);
FORCEADD TAP..6
(-3200 2950);
FORCEPROP 3 LASTPIN (-3150 2950) SIG_NAME M_K_ODT<1>
J 0
(-3140 2960);
DISPLAY 0.659574 (-3140 2960);
PAINT MONO (-3140 2960);
DISPLAY INVISIBLE (-3140 2960);
FORCEPROP 1 LASTPIN (-3150 2950) BN 1
J 0
(-3200 2960);
DISPLAY 0.617021 (-3200 2960);
PAINT PINK (-3200 2960);
FORCEPROP 2 LAST CDS_LIB mstr_standard
J 0
(-3200 2950);
DISPLAY 0.787234 (-3200 2950);
PAINT MONO (-3200 2950);
DISPLAY INVISIBLE (-3200 2950);
FORCEPROP 1 LAST BODY_TYPE PLUMBING
J 0
(-3200 2900);
DISPLAY 1.234043 (-3200 2900);
PAINT GREEN (-3200 2900);
DISPLAY INVISIBLE (-3200 2900);
FORCEPROP 1 LAST HDL_TAP TRUE
J 0
(-2875 2825);
DISPLAY 1.234043 (-2875 2825);
PAINT GREEN (-2875 2825);
DISPLAY INVISIBLE (-2875 2825);
FORCEPROP 1 LAST PATH I166
J 0
(-3200 2950);
DISPLAY 0.936170 (-3200 2950);
PAINT GREEN (-3200 2950);
DISPLAY INVISIBLE (-3200 2950);
FORCEADD SCONN288_H44441004..4
(-150 2100);
FORCEPROP 1 LAST LOCATION J1B1
J 0
(-600 3200);
DISPLAY 0.617021 (-600 3200);
PAINT AQUA (-600 3200);
FORCEPROP 1 LAST PART_NUMBER H44441-004
J 0
(-600 1050);
DISPLAY 0.617021 (-600 1050);
PAINT BLUE (-600 1050);
FORCEPROP 1 LAST MATERIAL SCONN
J 0
(-600 3150);
DISPLAY 0.617021 (-600 3150);
PAINT SKYBLUE (-600 3150);
FORCEPROP 2 LASTPIN (-650 2650) $PN 77
J 2
(-660 2660);
DISPLAY 0.617021 (-660 2660);
PAINT ORANGE (-660 2660);
FORCEPROP 2 LASTPIN (-650 2600) $PN 221
J 2
(-660 2610);
DISPLAY 0.617021 (-660 2610);
PAINT ORANGE (-660 2610);
FORCEPROP 2 LASTPIN (-650 2950) $PN 142
J 2
(-660 2960);
DISPLAY 0.617021 (-660 2960);
PAINT ORANGE (-660 2960);
FORCEPROP 2 LASTPIN (-650 2900) $PN 143
J 2
(-660 2910);
DISPLAY 0.617021 (-660 2910);
PAINT ORANGE (-660 2910);
FORCEPROP 2 LASTPIN (-650 2850) $PN 288
J 2
(-660 2860);
DISPLAY 0.617021 (-660 2860);
PAINT ORANGE (-660 2860);
FORCEPROP 2 LASTPIN (-650 2800) $PN 286
J 2
(-660 2810);
DISPLAY 0.617021 (-660 2810);
PAINT ORANGE (-660 2810);
FORCEPROP 2 LASTPIN (-650 2750) $PN 287
J 2
(-660 2760);
DISPLAY 0.617021 (-660 2760);
PAINT ORANGE (-660 2760);
FORCEPROP 2 LASTPIN (-650 2500) $PN 59
J 2
(-660 2510);
DISPLAY 0.617021 (-660 2510);
PAINT ORANGE (-660 2510);
FORCEPROP 2 LASTPIN (-650 2450) $PN 61
J 2
(-660 2460);
DISPLAY 0.617021 (-660 2460);
PAINT ORANGE (-660 2460);
FORCEPROP 2 LASTPIN (-650 2400) $PN 64
J 2
(-660 2410);
DISPLAY 0.617021 (-660 2410);
PAINT ORANGE (-660 2410);
FORCEPROP 2 LASTPIN (-650 2350) $PN 67
J 2
(-660 2360);
DISPLAY 0.617021 (-660 2360);
PAINT ORANGE (-660 2360);
FORCEPROP 2 LASTPIN (-650 2300) $PN 70
J 2
(-660 2310);
DISPLAY 0.617021 (-660 2310);
PAINT ORANGE (-660 2310);
FORCEPROP 2 LASTPIN (-650 2250) $PN 73
J 2
(-660 2260);
DISPLAY 0.617021 (-660 2260);
PAINT ORANGE (-660 2260);
FORCEPROP 2 LASTPIN (-650 2200) $PN 76
J 2
(-660 2210);
DISPLAY 0.617021 (-660 2210);
PAINT ORANGE (-660 2210);
FORCEPROP 2 LASTPIN (-650 2150) $PN 80
J 2
(-660 2160);
DISPLAY 0.617021 (-660 2160);
PAINT ORANGE (-660 2160);
FORCEPROP 2 LASTPIN (-650 2100) $PN 83
J 2
(-660 2110);
DISPLAY 0.617021 (-660 2110);
PAINT ORANGE (-660 2110);
FORCEPROP 2 LASTPIN (-650 2050) $PN 85
J 2
(-660 2060);
DISPLAY 0.617021 (-660 2060);
PAINT ORANGE (-660 2060);
FORCEPROP 2 LASTPIN (-650 2000) $PN 88
J 2
(-660 2010);
DISPLAY 0.617021 (-660 2010);
PAINT ORANGE (-660 2010);
FORCEPROP 2 LASTPIN (-650 1950) $PN 90
J 2
(-660 1960);
DISPLAY 0.617021 (-660 1960);
PAINT ORANGE (-660 1960);
FORCEPROP 2 LASTPIN (-650 1900) $PN 92
J 2
(-660 1910);
DISPLAY 0.617021 (-660 1910);
PAINT ORANGE (-660 1910);
FORCEPROP 2 LASTPIN (-650 1850) $PN 204
J 2
(-660 1860);
DISPLAY 0.617021 (-660 1860);
PAINT ORANGE (-660 1860);
FORCEPROP 2 LASTPIN (-650 1800) $PN 206
J 2
(-660 1810);
DISPLAY 0.617021 (-660 1810);
PAINT ORANGE (-660 1810);
FORCEPROP 2 LASTPIN (-650 1750) $PN 209
J 2
(-660 1760);
DISPLAY 0.617021 (-660 1760);
PAINT ORANGE (-660 1760);
FORCEPROP 2 LASTPIN (-650 1700) $PN 212
J 2
(-660 1710);
DISPLAY 0.617021 (-660 1710);
PAINT ORANGE (-660 1710);
FORCEPROP 2 LASTPIN (-650 1650) $PN 215
J 2
(-660 1660);
DISPLAY 0.617021 (-660 1660);
PAINT ORANGE (-660 1660);
FORCEPROP 2 LASTPIN (-650 1600) $PN 217
J 2
(-660 1610);
DISPLAY 0.617021 (-660 1610);
PAINT ORANGE (-660 1610);
FORCEPROP 2 LASTPIN (-650 1550) $PN 220
J 2
(-660 1560);
DISPLAY 0.617021 (-660 1560);
PAINT ORANGE (-660 1560);
FORCEPROP 2 LASTPIN (-650 1500) $PN 223
J 2
(-660 1510);
DISPLAY 0.617021 (-660 1510);
PAINT ORANGE (-660 1510);
FORCEPROP 2 LASTPIN (-650 1450) $PN 226
J 2
(-660 1460);
DISPLAY 0.617021 (-660 1460);
PAINT ORANGE (-660 1460);
FORCEPROP 2 LASTPIN (-650 1400) $PN 229
J 2
(-660 1410);
DISPLAY 0.617021 (-660 1410);
PAINT ORANGE (-660 1410);
FORCEPROP 2 LASTPIN (-650 1350) $PN 231
J 2
(-660 1360);
DISPLAY 0.617021 (-660 1360);
PAINT ORANGE (-660 1360);
FORCEPROP 2 LASTPIN (-650 1300) $PN 233
J 2
(-660 1310);
DISPLAY 0.617021 (-660 1310);
PAINT ORANGE (-660 1310);
FORCEPROP 2 LASTPIN (-650 1250) $PN 236
J 2
(-660 1260);
DISPLAY 0.617021 (-660 1260);
PAINT ORANGE (-660 1260);
FORCEPROP 2 LASTPIN (350 2950) $PN 1
J 0
(360 2960);
DISPLAY 0.617021 (360 2960);
PAINT ORANGE (360 2960);
FORCEPROP 2 LASTPIN (350 2900) $PN 145
J 0
(360 2910);
DISPLAY 0.617021 (360 2910);
PAINT ORANGE (360 2910);
FORCEPROP 1 LAST PACK_TYPE PIP
J 0
(-600 3250);
PAINT SKYBLUE (-600 3250);
DISPLAY INVISIBLE (-600 3250);
FORCEPROP 2 LAST BOM_COST MEM
J 0
(-150 2100);
PAINT ORANGE (-150 2100);
DISPLAY INVISIBLE (-150 2100);
FORCEPROP 2 LAST CDS_LIB mstr_sconn
J 0
(-150 2100);
PAINT ORANGE (-150 2100);
DISPLAY INVISIBLE (-150 2100);
FORCEPROP 2 LAST SEC_TYPE PIP
J 0
(-600 3250);
DISPLAY 1.021277 (-600 3250);
PAINT ORANGE (-600 3250);
DISPLAY INVISIBLE (-600 3250);
FORCEPROP 2 LAST SEC 4
J 0
(-600 3250);
DISPLAY 0.680851 (-600 3250);
PAINT MONO (-600 3250);
DISPLAY INVISIBLE (-600 3250);
FORCEPROP 2 LAST CDS_LOCATION J1B1
J 0
(-600 3200);
DISPLAY 0.617021 (-600 3200);
PAINT AQUA (-600 3200);
DISPLAY INVISIBLE (-600 3200);
FORCEPROP 1 LAST PATH I167
J 0
(-150 3150);
PAINT GREEN (-150 3150);
DISPLAY INVISIBLE (-150 3150);
FORCEPROP 2 LAST ROOM DDR4_CH_K
J 0
(-150 2100);
PAINT ORANGE (-150 2100);
DISPLAY INVISIBLE (-150 2100);
FORCEADD GND..1
R 2
(2500 1100);
FORCEPROP 3 LASTPIN (2500 1150) SIG_NAME GND\g
J 0
(2510 1160);
DISPLAY 0.659574 (2510 1160);
PAINT MONO (2510 1160);
DISPLAY INVISIBLE (2510 1160);
FORCEPROP 1 LAST VOLTAGE 0
J 0
(2500 1100);
PAINT SKYBLUE (2500 1100);
DISPLAY INVISIBLE (2500 1100);
FORCEPROP 2 LAST BOM_COST MEM
J 0
(2500 1105);
PAINT ORANGE (2500 1105);
DISPLAY INVISIBLE (2500 1105);
FORCEPROP 1 LAST SIZE 1B
J 2
(2425 1050);
DISPLAY 1.170213 (2425 1050);
PAINT GREEN (2425 1050);
DISPLAY INVISIBLE (2425 1050);
FORCEPROP 2 LAST CDS_LIB mstr_symbols
J 0
(2500 1100);
DISPLAY 0.787234 (2500 1100);
PAINT MONO (2500 1100);
DISPLAY INVISIBLE (2500 1100);
FORCEPROP 1 LAST BODY_TYPE PLUMBING
J 2
(2545 1057);
DISPLAY 0.340426 (2545 1057);
PAINT GREEN (2545 1057);
DISPLAY INVISIBLE (2545 1057);
FORCEPROP 1 LAST PATH I168
J 2
(2425 1100);
DISPLAY 1.404255 (2425 1100);
PAINT GREEN (2425 1100);
DISPLAY INVISIBLE (2425 1100);
FORCEPROP 2 LAST ROOM DDR4_CH_C
J 0
(2500 1105);
PAINT ORANGE (2500 1105);
DISPLAY INVISIBLE (2500 1105);
FORCEPROP 1 LAST HDL_POWER GND
J 2
(2500 1250);
DISPLAY 0.553191 (2500 1250);
PAINT GREEN (2500 1250);
DISPLAY INVISIBLE (2500 1250);
FORCEADD OFFPAGE..6
(-3800 1850);
FORCEPROP 2 LASTPIN (-3750 1850) SIG_NAME SMB_DDR_KLM_VPP_SDA
J 0
(-3710 1860);
DISPLAY 0.617021 (-3710 1860);
PAINT ORANGE (-3710 1860);
FORCEPROP 2 LAST $XR5 99 
J 0
(-4499 1850);
DISPLAY 0.638298 (-4499 1850);
PAINT MONO (-4499 1850);
FORCEPROP 2 LAST $XR4 88 
J 0
(-4409 1850);
DISPLAY 0.638298 (-4409 1850);
PAINT MONO (-4409 1850);
FORCEPROP 2 LAST $XR3 87 
J 0
(-4319 1850);
DISPLAY 0.638298 (-4319 1850);
PAINT MONO (-4319 1850);
FORCEPROP 2 LAST $XR2 86 
J 0
(-4229 1850);
DISPLAY 0.638298 (-4229 1850);
PAINT MONO (-4229 1850);
FORCEPROP 2 LAST $XR1 85 
J 0
(-4139 1850);
DISPLAY 0.638298 (-4139 1850);
PAINT MONO (-4139 1850);
FORCEPROP 2 LAST $XR0 84 
J 0
(-4049 1850);
DISPLAY 0.638298 (-4049 1850);
PAINT MONO (-4049 1850);
FORCEPROP 2 LAST CDS_LIB mstr_standard
J 0
(-3800 1850);
DISPLAY 0.787234 (-3800 1850);
PAINT MONO (-3800 1850);
DISPLAY INVISIBLE (-3800 1850);
FORCEPROP 1 LAST OFFPAGE TRUE
J 0
(-3475 1725);
DISPLAY 0.936170 (-3475 1725);
PAINT GREEN (-3475 1725);
DISPLAY INVISIBLE (-3475 1725);
FORCEPROP 1 LAST COMMENT_BODY TRUE
J 0
(-3700 1775);
DISPLAY 0.936170 (-3700 1775);
PAINT GREEN (-3700 1775);
DISPLAY INVISIBLE (-3700 1775);
FORCEPROP 2 LAST PATH I169
J 0
(-4100 1900);
DISPLAY 0.787234 (-4100 1900);
PAINT ORANGE (-4100 1900);
DISPLAY INVISIBLE (-4100 1900);
FORCEADD PVTT_KLM..1
(-1050 2800);
FORCEPROP 3 LASTPIN (-1050 2750) SIG_NAME PVTT_KLM\g
J 0
(-1040 2760);
DISPLAY 0.659574 (-1040 2760);
PAINT MONO (-1040 2760);
DISPLAY INVISIBLE (-1040 2760);
FORCEPROP 1 LAST VOLTAGE 0.6V
J 0
(-1095 2757);
DISPLAY 0.340426 (-1095 2757);
PAINT SKYBLUE (-1095 2757);
DISPLAY INVISIBLE (-1095 2757);
FORCEPROP 2 LAST BOM_COST MEM
J 0
(-1050 2805);
PAINT ORANGE (-1050 2805);
DISPLAY INVISIBLE (-1050 2805);
FORCEPROP 2 LAST CDS_LIB mstr_symbols
J 0
(-1050 2800);
PAINT ORANGE (-1050 2800);
DISPLAY INVISIBLE (-1050 2800);
FORCEPROP 1 LAST BODY_TYPE PLUMBING
J 0
(-1095 2757);
DISPLAY 0.340426 (-1095 2757);
PAINT GREEN (-1095 2757);
DISPLAY INVISIBLE (-1095 2757);
FORCEPROP 1 LAST PATH I17
J 0
(-1000 2825);
DISPLAY 0.872340 (-1000 2825);
PAINT AQUA (-1000 2825);
DISPLAY INVISIBLE (-1000 2825);
FORCEPROP 2 LAST ROOM DDR4_CH_C
J 0
(-1050 2900);
DISPLAY 0.787234 (-1050 2900);
PAINT ORANGE (-1050 2900);
DISPLAY INVISIBLE (-1050 2900);
FORCEPROP 1 LAST HDL_POWER PVTT_KLM
J 1
(-1050 2850);
DISPLAY 0.872340 (-1050 2850);
PAINT GREEN (-1050 2850);
DISPLAY INVISIBLE (-1050 2850);
FORCEADD OFFPAGE..1
(-3800 1800);
FORCEPROP 2 LAST $XR5 88 
J 0
(-4501 1800);
DISPLAY 0.638298 (-4501 1800);
PAINT MONO (-4501 1800);
FORCEPROP 2 LAST $XR4 87 
J 0
(-4411 1800);
DISPLAY 0.638298 (-4411 1800);
PAINT MONO (-4411 1800);
FORCEPROP 2 LAST $XR3 86 
J 0
(-4321 1800);
DISPLAY 0.638298 (-4321 1800);
PAINT MONO (-4321 1800);
FORCEPROP 2 LAST $XR2 85 
J 0
(-4231 1800);
DISPLAY 0.638298 (-4231 1800);
PAINT MONO (-4231 1800);
FORCEPROP 2 LAST $XR1 84 
J 0
(-4141 1800);
DISPLAY 0.638298 (-4141 1800);
PAINT MONO (-4141 1800);
FORCEPROP 2 LAST $XR0 99 
J 0
(-4051 1800);
DISPLAY 0.638298 (-4051 1800);
PAINT MONO (-4051 1800);
FORCEPROP 2 LAST CDS_LIB mstr_standard
J 0
(-3800 1800);
DISPLAY 0.787234 (-3800 1800);
PAINT MONO (-3800 1800);
DISPLAY INVISIBLE (-3800 1800);
FORCEPROP 1 LAST OFFPAGE TRUE
J 0
(-3475 1675);
DISPLAY 0.936170 (-3475 1675);
PAINT GREEN (-3475 1675);
DISPLAY INVISIBLE (-3475 1675);
FORCEPROP 1 LAST COMMENT_BODY TRUE
J 0
(-3675 1700);
DISPLAY 0.936170 (-3675 1700);
PAINT GREEN (-3675 1700);
DISPLAY INVISIBLE (-3675 1700);
FORCEPROP 2 LAST PATH I170
J 0
(-4075 1850);
DISPLAY 0.787234 (-4075 1850);
PAINT ORANGE (-4075 1850);
DISPLAY INVISIBLE (-4075 1850);
FORCEADD OFFPAGE..1
(-4750 1700);
FORCEPROP 2 LAST $XR1 84 
J 0
(-5092 1700);
DISPLAY 0.638298 (-5092 1700);
PAINT MONO (-5092 1700);
FORCEPROP 2 LAST $XR0 100 
J 0
(-5002 1700);
DISPLAY 0.638298 (-5002 1700);
PAINT MONO (-5002 1700);
FORCEPROP 2 LAST CDS_LIB mstr_standard
J 0
(-4750 1700);
DISPLAY 0.787234 (-4750 1700);
PAINT MONO (-4750 1700);
DISPLAY INVISIBLE (-4750 1700);
FORCEPROP 1 LAST OFFPAGE TRUE
J 0
(-4425 1575);
DISPLAY 0.936170 (-4425 1575);
PAINT GREEN (-4425 1575);
DISPLAY INVISIBLE (-4425 1575);
FORCEPROP 1 LAST COMMENT_BODY TRUE
J 0
(-4625 1600);
DISPLAY 0.936170 (-4625 1600);
PAINT GREEN (-4625 1600);
DISPLAY INVISIBLE (-4625 1600);
FORCEPROP 2 LAST PATH I171
J 0
(-5000 1750);
DISPLAY 0.787234 (-5000 1750);
PAINT ORANGE (-5000 1750);
DISPLAY INVISIBLE (-5000 1750);
FORCEADD GND..1
R 2
(-5100 1850);
FORCEPROP 3 LASTPIN (-5100 1900) SIG_NAME GND\g
J 0
(-5090 1910);
DISPLAY 0.659574 (-5090 1910);
PAINT MONO (-5090 1910);
DISPLAY INVISIBLE (-5090 1910);
FORCEPROP 1 LAST VOLTAGE 0
J 0
(-5100 1850);
PAINT SKYBLUE (-5100 1850);
DISPLAY INVISIBLE (-5100 1850);
FORCEPROP 2 LAST BOM_COST MEM
J 0
(-5100 1855);
PAINT ORANGE (-5100 1855);
DISPLAY INVISIBLE (-5100 1855);
FORCEPROP 2 LAST CDS_LIB mstr_symbols
J 0
(-5100 1850);
DISPLAY 0.787234 (-5100 1850);
PAINT MONO (-5100 1850);
DISPLAY INVISIBLE (-5100 1850);
FORCEPROP 1 LAST SIZE 1B
J 2
(-5175 1800);
DISPLAY 1.170213 (-5175 1800);
PAINT GREEN (-5175 1800);
DISPLAY INVISIBLE (-5175 1800);
FORCEPROP 1 LAST BODY_TYPE PLUMBING
J 2
(-5055 1807);
DISPLAY 0.340426 (-5055 1807);
PAINT GREEN (-5055 1807);
DISPLAY INVISIBLE (-5055 1807);
FORCEPROP 1 LAST PATH I173
J 2
(-5175 1850);
DISPLAY 1.404255 (-5175 1850);
PAINT GREEN (-5175 1850);
DISPLAY INVISIBLE (-5175 1850);
FORCEPROP 2 LAST ROOM DDR4_CH_C
J 0
(-5100 1855);
PAINT ORANGE (-5100 1855);
DISPLAY INVISIBLE (-5100 1855);
FORCEPROP 1 LAST HDL_POWER GND
J 2
(-5100 2000);
DISPLAY 0.553191 (-5100 2000);
PAINT GREEN (-5100 2000);
DISPLAY INVISIBLE (-5100 2000);
FORCEADD OFFPAGE..5
(-4175 2550);
FORCEPROP 2 LAST $XR23 94 
J 0
(-4789 2586);
DISPLAY 0.638298 (-4789 2586);
PAINT MONO (-4789 2586);
FORCEPROP 2 LAST $XR22 88 
J 0
(-4699 2586);
DISPLAY 0.638298 (-4699 2586);
PAINT MONO (-4699 2586);
FORCEPROP 2 LAST $XR21 87 
J 0
(-4609 2586);
DISPLAY 0.638298 (-4609 2586);
PAINT MONO (-4609 2586);
FORCEPROP 2 LAST $XR20 86 
J 0
(-4519 2586);
DISPLAY 0.638298 (-4519 2586);
PAINT MONO (-4519 2586);
FORCEPROP 2 LAST $XR19 85 
J 0
(-4429 2586);
DISPLAY 0.638298 (-4429 2586);
PAINT MONO (-4429 2586);
FORCEPROP 2 LAST $XR18 84 
J 0
(-5149 2514);
DISPLAY 0.638298 (-5149 2514);
PAINT MONO (-5149 2514);
FORCEPROP 2 LAST $XR17 82 
J 0
(-5059 2514);
DISPLAY 0.638298 (-5059 2514);
PAINT MONO (-5059 2514);
FORCEPROP 2 LAST $XR16 81 
J 0
(-4969 2514);
DISPLAY 0.638298 (-4969 2514);
PAINT MONO (-4969 2514);
FORCEPROP 2 LAST $XR15 80 
J 0
(-4879 2514);
DISPLAY 0.638298 (-4879 2514);
PAINT MONO (-4879 2514);
FORCEPROP 2 LAST $XR14 79 
J 0
(-4789 2514);
DISPLAY 0.638298 (-4789 2514);
PAINT MONO (-4789 2514);
FORCEPROP 2 LAST $XR13 78 
J 0
(-4699 2514);
DISPLAY 0.638298 (-4699 2514);
PAINT MONO (-4699 2514);
FORCEPROP 2 LAST $XR12 77 
J 0
(-4609 2514);
DISPLAY 0.638298 (-4609 2514);
PAINT MONO (-4609 2514);
FORCEPROP 2 LAST $XR11 54 
J 0
(-4519 2514);
DISPLAY 0.638298 (-4519 2514);
PAINT MONO (-4519 2514);
FORCEPROP 2 LAST $XR10 53 
J 0
(-4429 2514);
DISPLAY 0.638298 (-4429 2514);
PAINT MONO (-4429 2514);
FORCEPROP 2 LAST $XR9 52 
J 0
(-5239 2550);
DISPLAY 0.638298 (-5239 2550);
PAINT MONO (-5239 2550);
FORCEPROP 2 LAST $XR8 51 
J 0
(-5149 2550);
DISPLAY 0.638298 (-5149 2550);
PAINT MONO (-5149 2550);
FORCEPROP 2 LAST $XR7 50 
J 0
(-5059 2550);
DISPLAY 0.638298 (-5059 2550);
PAINT MONO (-5059 2550);
FORCEPROP 2 LAST $XR6 49 
J 0
(-4969 2550);
DISPLAY 0.638298 (-4969 2550);
PAINT MONO (-4969 2550);
FORCEPROP 2 LAST $XR5 48 
J 0
(-4879 2550);
DISPLAY 0.638298 (-4879 2550);
PAINT MONO (-4879 2550);
FORCEPROP 2 LAST $XR4 47 
J 0
(-4789 2550);
DISPLAY 0.638298 (-4789 2550);
PAINT MONO (-4789 2550);
FORCEPROP 2 LAST $XR3 46 
J 0
(-4699 2550);
DISPLAY 0.638298 (-4699 2550);
PAINT MONO (-4699 2550);
FORCEPROP 2 LAST $XR2 45 
J 0
(-4609 2550);
DISPLAY 0.638298 (-4609 2550);
PAINT MONO (-4609 2550);
FORCEPROP 2 LAST $XR1 44 
J 0
(-4519 2550);
DISPLAY 0.638298 (-4519 2550);
PAINT MONO (-4519 2550);
FORCEPROP 2 LAST $XR0 43 
J 0
(-4429 2550);
DISPLAY 0.638298 (-4429 2550);
PAINT MONO (-4429 2550);
FORCEPROP 2 LAST CDS_LIB mstr_standard
J 0
(-4175 2550);
DISPLAY 0.787234 (-4175 2550);
PAINT MONO (-4175 2550);
DISPLAY INVISIBLE (-4175 2550);
FORCEPROP 1 LAST OFFPAGE TRUE
J 0
(-3850 2425);
DISPLAY 1.404255 (-3850 2425);
PAINT GREEN (-3850 2425);
DISPLAY INVISIBLE (-3850 2425);
FORCEPROP 1 LAST COMMENT_BODY TRUE
J 0
(-4075 2475);
DISPLAY 1.404255 (-4075 2475);
PAINT GREEN (-4075 2475);
DISPLAY INVISIBLE (-4075 2475);
FORCEPROP 2 LAST PATH I174
J 0
(-4125 2625);
DISPLAY 0.787234 (-4125 2625);
PAINT ORANGE (-4125 2625);
DISPLAY INVISIBLE (-4125 2625);
FORCEADD GND..1
(-4600 1250);
FORCEPROP 3 LASTPIN (-4600 1300) SIG_NAME GND\g
J 0
(-4590 1310);
DISPLAY 0.659574 (-4590 1310);
PAINT MONO (-4590 1310);
DISPLAY INVISIBLE (-4590 1310);
FORCEPROP 1 LAST VOLTAGE 0
J 0
(-4600 1250);
PAINT SKYBLUE (-4600 1250);
DISPLAY INVISIBLE (-4600 1250);
FORCEPROP 2 LAST BOM_COST MEM
J 0
(-4600 1255);
PAINT ORANGE (-4600 1255);
DISPLAY INVISIBLE (-4600 1255);
FORCEPROP 1 LAST SIZE 1B
J 0
(-4525 1200);
DISPLAY 1.787234 (-4525 1200);
PAINT GREEN (-4525 1200);
DISPLAY INVISIBLE (-4525 1200);
FORCEPROP 2 LAST CDS_LIB mstr_symbols
J 0
(-4600 1250);
PAINT ORANGE (-4600 1250);
DISPLAY INVISIBLE (-4600 1250);
FORCEPROP 1 LAST BODY_TYPE PLUMBING
J 0
(-4645 1207);
DISPLAY 0.340426 (-4645 1207);
PAINT GREEN (-4645 1207);
DISPLAY INVISIBLE (-4645 1207);
FORCEPROP 1 LAST PATH I175
J 0
(-4525 1250);
DISPLAY 1.404255 (-4525 1250);
PAINT GREEN (-4525 1250);
DISPLAY INVISIBLE (-4525 1250);
FORCEPROP 2 LAST ROOM DDR4_CH_C
J 0
(-4600 1255);
PAINT ORANGE (-4600 1255);
DISPLAY INVISIBLE (-4600 1255);
FORCEPROP 1 LAST HDL_POWER GND
J 0
(-4600 1400);
DISPLAY 1.404255 (-4600 1400);
PAINT GREEN (-4600 1400);
DISPLAY INVISIBLE (-4600 1400);
FORCEADD CAP_A..1
R 2
(-4600 1500);
FORCEPROP 1 LAST LOCATION C1B9
J 2
(-4650 1600);
DISPLAY 0.617021 (-4650 1600);
PAINT AQUA (-4650 1600);
FORCEPROP 1 LAST PART_NUMBER A36096-045
J 2
(-4650 1350);
DISPLAY 0.617021 (-4650 1350);
PAINT BLUE (-4650 1350);
FORCEPROP 1 LAST VALUE 0.01UF
J 2
(-4650 1550);
DISPLAY 0.617021 (-4650 1550);
PAINT SKYBLUE (-4650 1550);
FORCEPROP 1 LAST TOLERANCE 10%
J 2
(-4650 1450);
DISPLAY 0.617021 (-4650 1450);
PAINT SKYBLUE (-4650 1450);
FORCEPROP 1 LAST PACK_TYPE 0402V
J 2
(-4650 1300);
DISPLAY 0.617021 (-4650 1300);
PAINT SKYBLUE (-4650 1300);
FORCEPROP 1 LAST VOLTAGE 25V
J 2
(-4650 1500);
DISPLAY 0.617021 (-4650 1500);
PAINT SKYBLUE (-4650 1500);
FORCEPROP 1 LAST MATERIAL X7R
J 2
(-4650 1400);
DISPLAY 0.617021 (-4650 1400);
PAINT SKYBLUE (-4650 1400);
FORCEPROP 2 LAST CDS_LOCATION C1B9
J 2
(-4650 1600);
DISPLAY 0.617021 (-4650 1600);
PAINT AQUA (-4650 1600);
DISPLAY INVISIBLE (-4650 1600);
FORCEPROP 2 LAST BOM_COST MEM
J 0
(-4600 1500);
PAINT ORANGE (-4600 1500);
DISPLAY INVISIBLE (-4600 1500);
FORCEPROP 2 LAST CDS_LIB dev_discrete
J 0
(-4600 1500);
PAINT ORANGE (-4600 1500);
DISPLAY INVISIBLE (-4600 1500);
FORCEPROP 2 LAST CDS_SEC 1
J 2
(-4650 1700);
PAINT MONO (-4650 1700);
DISPLAY INVISIBLE (-4650 1700);
FORCEPROP 2 LAST $SEC 1
J 0
(-4650 1700);
PAINT MONO (-4650 1700);
DISPLAY INVISIBLE (-4650 1700);
FORCEPROP 1 LAST PATH I176
J 2
(-4650 1650);
DISPLAY 0.978723 (-4650 1650);
PAINT WHITE (-4650 1650);
DISPLAY INVISIBLE (-4650 1650);
FORCEPROP 2 LAST ROOM DDR4_CH_K
J 0
(-4600 1500);
PAINT ORANGE (-4600 1500);
DISPLAY INVISIBLE (-4600 1500);
FORCEPROP 1 LASTPIN (-4600 1600) $PN 1
J 2
(-4610 1580);
DISPLAY 0.787234 (-4610 1580);
PAINT ORANGE (-4610 1580);
DISPLAY INVISIBLE (-4610 1580);
FORCEPROP 1 LASTPIN (-4600 1400) $PN 2
J 2
(-4610 1380);
DISPLAY 0.787234 (-4610 1380);
PAINT ORANGE (-4610 1380);
DISPLAY INVISIBLE (-4610 1380);
FORCEADD PVPP_KLM..1
(-850 3100);
FORCEPROP 3 LASTPIN (-850 3050) SIG_NAME PVPP_KLM\g
J 0
(-840 3060);
DISPLAY 0.659574 (-840 3060);
PAINT MONO (-840 3060);
DISPLAY INVISIBLE (-840 3060);
FORCEPROP 1 LAST VOLTAGE 2.5V
J 0
(-895 3057);
DISPLAY 0.340426 (-895 3057);
PAINT SKYBLUE (-895 3057);
DISPLAY INVISIBLE (-895 3057);
FORCEPROP 0 LAST BOM_COST MEM
J 0
(-850 3200);
PAINT ORANGE (-850 3200);
DISPLAY INVISIBLE (-850 3200);
FORCEPROP 2 LAST CDS_LIB mstr_symbols
J 0
(-850 3100);
PAINT ORANGE (-850 3100);
DISPLAY INVISIBLE (-850 3100);
FORCEPROP 1 LAST BODY_TYPE PLUMBING
J 0
(-895 3057);
DISPLAY 0.340426 (-895 3057);
PAINT GREEN (-895 3057);
DISPLAY INVISIBLE (-895 3057);
FORCEPROP 1 LAST PATH I177
J 0
(-800 3125);
DISPLAY 0.872340 (-800 3125);
PAINT AQUA (-800 3125);
DISPLAY INVISIBLE (-800 3125);
FORCEPROP 2 LAST ROOM DDR4_CH_C
J 0
(-850 3200);
PAINT ORANGE (-850 3200);
DISPLAY INVISIBLE (-850 3200);
FORCEPROP 1 LAST HDL_POWER PVPP_KLM
J 1
(-850 3150);
DISPLAY 0.872340 (-850 3150);
PAINT GREEN (-850 3150);
DISPLAY INVISIBLE (-850 3150);
FORCEADD PVPP_KLM..1
(-5100 2200);
FORCEPROP 3 LASTPIN (-5100 2150) SIG_NAME PVPP_KLM\g
J 0
(-5090 2160);
DISPLAY 0.659574 (-5090 2160);
PAINT MONO (-5090 2160);
DISPLAY INVISIBLE (-5090 2160);
FORCEPROP 1 LAST VOLTAGE 2.5V
J 0
(-5145 2157);
DISPLAY 0.340426 (-5145 2157);
PAINT SKYBLUE (-5145 2157);
DISPLAY INVISIBLE (-5145 2157);
FORCEPROP 0 LAST BOM_COST MEM
J 0
(-5100 2300);
PAINT ORANGE (-5100 2300);
DISPLAY INVISIBLE (-5100 2300);
FORCEPROP 2 LAST CDS_LIB mstr_symbols
J 0
(-5100 2200);
PAINT ORANGE (-5100 2200);
DISPLAY INVISIBLE (-5100 2200);
FORCEPROP 1 LAST BODY_TYPE PLUMBING
J 0
(-5145 2157);
DISPLAY 0.340426 (-5145 2157);
PAINT GREEN (-5145 2157);
DISPLAY INVISIBLE (-5145 2157);
FORCEPROP 1 LAST PATH I178
J 0
(-5050 2225);
DISPLAY 0.872340 (-5050 2225);
PAINT AQUA (-5050 2225);
DISPLAY INVISIBLE (-5050 2225);
FORCEPROP 2 LAST ROOM DDR4_CH_C
J 0
(-5100 2300);
PAINT ORANGE (-5100 2300);
DISPLAY INVISIBLE (-5100 2300);
FORCEPROP 1 LAST HDL_POWER PVPP_KLM
J 1
(-5100 2250);
DISPLAY 0.872340 (-5100 2250);
PAINT GREEN (-5100 2250);
DISPLAY INVISIBLE (-5100 2250);
FORCEADD OFFPAGE..1
(-3850 1400);
FORCEPROP 2 LAST $XR5 88 
J 0
(-4551 1400);
DISPLAY 0.638298 (-4551 1400);
PAINT MONO (-4551 1400);
FORCEPROP 2 LAST $XR4 87 
J 0
(-4461 1400);
DISPLAY 0.638298 (-4461 1400);
PAINT MONO (-4461 1400);
FORCEPROP 2 LAST $XR3 86 
J 0
(-4371 1400);
DISPLAY 0.638298 (-4371 1400);
PAINT MONO (-4371 1400);
FORCEPROP 2 LAST $XR2 85 
J 0
(-4281 1400);
DISPLAY 0.638298 (-4281 1400);
PAINT MONO (-4281 1400);
FORCEPROP 2 LAST $XR1 84 
J 0
(-4191 1400);
DISPLAY 0.638298 (-4191 1400);
PAINT MONO (-4191 1400);
FORCEPROP 2 LAST $XR0 89 
J 0
(-4101 1400);
DISPLAY 0.638298 (-4101 1400);
PAINT MONO (-4101 1400);
FORCEPROP 2 LAST CDS_LIB mstr_standard
J 0
(-3850 1400);
PAINT ORANGE (-3850 1400);
DISPLAY INVISIBLE (-3850 1400);
FORCEPROP 1 LAST OFFPAGE TRUE
J 0
(-3525 1275);
DISPLAY 0.936170 (-3525 1275);
PAINT GREEN (-3525 1275);
DISPLAY INVISIBLE (-3525 1275);
FORCEPROP 1 LAST COMMENT_BODY TRUE
J 0
(-3725 1300);
DISPLAY 0.936170 (-3725 1300);
PAINT GREEN (-3725 1300);
DISPLAY INVISIBLE (-3725 1300);
FORCEPROP 2 LAST PATH I179
J 0
(-3800 1475);
PAINT ORANGE (-3800 1475);
DISPLAY INVISIBLE (-3800 1475);
FORCEADD TAP..6
(-3700 3600);
FORCEPROP 3 LASTPIN (-3650 3600) SIG_NAME M_K_CLK_DN<1>
J 0
(-3640 3610);
DISPLAY 0.659574 (-3640 3610);
PAINT MONO (-3640 3610);
DISPLAY INVISIBLE (-3640 3610);
FORCEPROP 1 LASTPIN (-3650 3600) BN 1
J 0
(-3702 3608);
DISPLAY 0.617021 (-3702 3608);
PAINT PINK (-3702 3608);
FORCEPROP 2 LAST CDS_LIB mstr_standard
J 0
(-3700 3600);
PAINT MONO (-3700 3600);
DISPLAY INVISIBLE (-3700 3600);
FORCEPROP 1 LAST BODY_TYPE PLUMBING
J 0
(-3700 3550);
DISPLAY 1.234043 (-3700 3550);
PAINT GREEN (-3700 3550);
DISPLAY INVISIBLE (-3700 3550);
FORCEPROP 1 LAST HDL_TAP TRUE
J 0
(-3375 3475);
DISPLAY 1.234043 (-3375 3475);
PAINT GREEN (-3375 3475);
DISPLAY INVISIBLE (-3375 3475);
FORCEPROP 1 LAST PATH I183
J 0
(-3702 3600);
DISPLAY 0.872340 (-3702 3600);
PAINT GREEN (-3702 3600);
DISPLAY INVISIBLE (-3702 3600);
FORCEADD TAP..6
(-3550 3650);
FORCEPROP 3 LASTPIN (-3500 3650) SIG_NAME M_K_CLK_DP<1>
J 0
(-3490 3660);
DISPLAY 0.659574 (-3490 3660);
PAINT MONO (-3490 3660);
DISPLAY INVISIBLE (-3490 3660);
FORCEPROP 1 LASTPIN (-3500 3650) BN 1
J 0
(-3552 3658);
DISPLAY 0.617021 (-3552 3658);
PAINT PINK (-3552 3658);
FORCEPROP 2 LAST CDS_LIB mstr_standard
J 0
(-3550 3650);
PAINT MONO (-3550 3650);
DISPLAY INVISIBLE (-3550 3650);
FORCEPROP 1 LAST BODY_TYPE PLUMBING
J 0
(-3550 3600);
DISPLAY 1.234043 (-3550 3600);
PAINT GREEN (-3550 3600);
DISPLAY INVISIBLE (-3550 3600);
FORCEPROP 1 LAST HDL_TAP TRUE
J 0
(-3225 3525);
DISPLAY 1.234043 (-3225 3525);
PAINT GREEN (-3225 3525);
DISPLAY INVISIBLE (-3225 3525);
FORCEPROP 1 LAST PATH I184
J 0
(-3552 3650);
DISPLAY 0.872340 (-3552 3650);
PAINT GREEN (-3552 3650);
DISPLAY INVISIBLE (-3552 3650);
FORCEADD P12V_NVDIMM_KLM..1
(550 3175);
FORCEPROP 3 LASTPIN (550 3125) SIG_NAME P12V_NVDIMM_KLM\g
J 0
(560 3135);
DISPLAY 0.659574 (560 3135);
PAINT MONO (560 3135);
DISPLAY INVISIBLE (560 3135);
FORCEPROP 1 LAST VOLTAGE 12.0
J 0
(505 3132);
DISPLAY 0.340426 (505 3132);
PAINT SKYBLUE (505 3132);
DISPLAY INVISIBLE (505 3132);
FORCEPROP 2 LAST CDS_LIB mstr_symbols
J 0
(550 3175);
PAINT ORANGE (550 3175);
DISPLAY INVISIBLE (550 3175);
FORCEPROP 1 LAST BODY_TYPE PLUMBING
J 0
(505 3132);
DISPLAY 0.340426 (505 3132);
PAINT GREEN (505 3132);
DISPLAY INVISIBLE (505 3132);
FORCEPROP 1 LAST PATH I185
J 0
(600 3200);
DISPLAY 0.872340 (600 3200);
PAINT AQUA (600 3200);
DISPLAY INVISIBLE (600 3200);
FORCEPROP 1 LAST HDL_POWER P12V_NVDIMM_KLM
J 1
(550 3225);
DISPLAY 0.872340 (550 3225);
PAINT GREEN (550 3225);
DISPLAY INVISIBLE (550 3225);
FORCEADD TAP..6
R 2
(900 4550);
FORCEPROP 3 LASTPIN (850 4550) SIG_NAME M_K_DQS_DN<11>
J 0
(860 4560);
DISPLAY 0.659574 (860 4560);
PAINT MONO (860 4560);
DISPLAY INVISIBLE (860 4560);
FORCEPROP 1 LASTPIN (850 4550) BN 11
J 2
(900 4560);
DISPLAY 0.617021 (900 4560);
PAINT PINK (900 4560);
FORCEPROP 2 LAST CDS_LIB mstr_standard
J 0
(900 4550);
DISPLAY 0.787234 (900 4550);
PAINT MONO (900 4550);
DISPLAY INVISIBLE (900 4550);
FORCEPROP 1 LAST BODY_TYPE PLUMBING
J 2
(900 4500);
DISPLAY 1.234043 (900 4500);
PAINT GREEN (900 4500);
DISPLAY INVISIBLE (900 4500);
FORCEPROP 1 LAST HDL_TAP TRUE
J 2
(575 4425);
DISPLAY 1.234043 (575 4425);
PAINT GREEN (575 4425);
DISPLAY INVISIBLE (575 4425);
FORCEPROP 1 LAST PATH I19
J 2
(900 4550);
DISPLAY 0.936170 (900 4550);
PAINT GREEN (900 4550);
DISPLAY INVISIBLE (900 4550);
FORCEADD OFFPAGE..3
(1600 5200);
FORCEPROP 2 LAST $XR1 84 
J 0
(1904 5200);
DISPLAY 0.638298 (1904 5200);
PAINT MONO (1904 5200);
FORCEPROP 2 LAST $XR0 60 
J 0
(1814 5200);
DISPLAY 0.638298 (1814 5200);
PAINT MONO (1814 5200);
FORCEPROP 2 LAST CDS_LIB mstr_standard
J 0
(1600 5200);
DISPLAY 0.787234 (1600 5200);
PAINT MONO (1600 5200);
DISPLAY INVISIBLE (1600 5200);
FORCEPROP 1 LAST OFFPAGE TRUE
J 0
(1925 5075);
DISPLAY 0.936170 (1925 5075);
PAINT GREEN (1925 5075);
DISPLAY INVISIBLE (1925 5075);
FORCEPROP 1 LAST COMMENT_BODY TRUE
J 0
(1550 5100);
DISPLAY 0.936170 (1550 5100);
PAINT GREEN (1550 5100);
DISPLAY INVISIBLE (1550 5100);
FORCEPROP 2 LAST PATH I2
J 0
(1800 5275);
DISPLAY 0.787234 (1800 5275);
PAINT MONO (1800 5275);
DISPLAY INVISIBLE (1800 5275);
FORCEADD TAP..6
R 2
(900 4450);
FORCEPROP 3 LASTPIN (850 4450) SIG_NAME M_K_DQS_DN<10>
J 0
(860 4460);
DISPLAY 0.659574 (860 4460);
PAINT MONO (860 4460);
DISPLAY INVISIBLE (860 4460);
FORCEPROP 1 LASTPIN (850 4450) BN 10
J 2
(900 4460);
DISPLAY 0.617021 (900 4460);
PAINT PINK (900 4460);
FORCEPROP 2 LAST CDS_LIB mstr_standard
J 0
(900 4450);
DISPLAY 0.787234 (900 4450);
PAINT MONO (900 4450);
DISPLAY INVISIBLE (900 4450);
FORCEPROP 1 LAST BODY_TYPE PLUMBING
J 2
(900 4400);
DISPLAY 1.234043 (900 4400);
PAINT GREEN (900 4400);
DISPLAY INVISIBLE (900 4400);
FORCEPROP 1 LAST HDL_TAP TRUE
J 2
(575 4325);
DISPLAY 1.234043 (575 4325);
PAINT GREEN (575 4325);
DISPLAY INVISIBLE (575 4325);
FORCEPROP 1 LAST PATH I20
J 2
(900 4450);
DISPLAY 0.936170 (900 4450);
PAINT GREEN (900 4450);
DISPLAY INVISIBLE (900 4450);
FORCEADD TAP..6
R 2
(900 4350);
FORCEPROP 3 LASTPIN (850 4350) SIG_NAME M_K_DQS_DN<9>
J 0
(860 4360);
DISPLAY 0.659574 (860 4360);
PAINT MONO (860 4360);
DISPLAY INVISIBLE (860 4360);
FORCEPROP 1 LASTPIN (850 4350) BN 9
J 2
(900 4360);
DISPLAY 0.617021 (900 4360);
PAINT PINK (900 4360);
FORCEPROP 2 LAST CDS_LIB mstr_standard
J 0
(900 4350);
DISPLAY 0.787234 (900 4350);
PAINT MONO (900 4350);
DISPLAY INVISIBLE (900 4350);
FORCEPROP 1 LAST BODY_TYPE PLUMBING
J 2
(900 4300);
DISPLAY 1.234043 (900 4300);
PAINT GREEN (900 4300);
DISPLAY INVISIBLE (900 4300);
FORCEPROP 1 LAST HDL_TAP TRUE
J 2
(575 4225);
DISPLAY 1.234043 (575 4225);
PAINT GREEN (575 4225);
DISPLAY INVISIBLE (575 4225);
FORCEPROP 1 LAST PATH I21
J 2
(900 4350);
DISPLAY 0.936170 (900 4350);
PAINT GREEN (900 4350);
DISPLAY INVISIBLE (900 4350);
FORCEADD TAP..6
R 2
(900 4250);
FORCEPROP 3 LASTPIN (850 4250) SIG_NAME M_K_DQS_DN<8>
J 0
(860 4260);
DISPLAY 0.659574 (860 4260);
PAINT MONO (860 4260);
DISPLAY INVISIBLE (860 4260);
FORCEPROP 1 LASTPIN (850 4250) BN 8
J 2
(900 4260);
DISPLAY 0.617021 (900 4260);
PAINT PINK (900 4260);
FORCEPROP 2 LAST CDS_LIB mstr_standard
J 0
(900 4250);
DISPLAY 0.787234 (900 4250);
PAINT MONO (900 4250);
DISPLAY INVISIBLE (900 4250);
FORCEPROP 1 LAST BODY_TYPE PLUMBING
J 2
(900 4200);
DISPLAY 1.234043 (900 4200);
PAINT GREEN (900 4200);
DISPLAY INVISIBLE (900 4200);
FORCEPROP 1 LAST HDL_TAP TRUE
J 2
(575 4125);
DISPLAY 1.234043 (575 4125);
PAINT GREEN (575 4125);
DISPLAY INVISIBLE (575 4125);
FORCEPROP 1 LAST PATH I22
J 2
(900 4250);
DISPLAY 0.936170 (900 4250);
PAINT GREEN (900 4250);
DISPLAY INVISIBLE (900 4250);
FORCEADD TAP..6
R 2
(900 4150);
FORCEPROP 3 LASTPIN (850 4150) SIG_NAME M_K_DQS_DN<7>
J 0
(860 4160);
DISPLAY 0.659574 (860 4160);
PAINT MONO (860 4160);
DISPLAY INVISIBLE (860 4160);
FORCEPROP 1 LASTPIN (850 4150) BN 7
J 2
(900 4160);
DISPLAY 0.617021 (900 4160);
PAINT PINK (900 4160);
FORCEPROP 2 LAST CDS_LIB mstr_standard
J 0
(900 4150);
DISPLAY 0.787234 (900 4150);
PAINT MONO (900 4150);
DISPLAY INVISIBLE (900 4150);
FORCEPROP 1 LAST BODY_TYPE PLUMBING
J 2
(900 4100);
DISPLAY 1.234043 (900 4100);
PAINT GREEN (900 4100);
DISPLAY INVISIBLE (900 4100);
FORCEPROP 1 LAST HDL_TAP TRUE
J 2
(575 4025);
DISPLAY 1.234043 (575 4025);
PAINT GREEN (575 4025);
DISPLAY INVISIBLE (575 4025);
FORCEPROP 1 LAST PATH I23
J 2
(900 4150);
DISPLAY 0.936170 (900 4150);
PAINT GREEN (900 4150);
DISPLAY INVISIBLE (900 4150);
FORCEADD TAP..6
R 2
(700 4500);
FORCEPROP 3 LASTPIN (650 4500) SIG_NAME M_K_DQS_DP<10>
J 0
(660 4510);
DISPLAY 0.659574 (660 4510);
PAINT MONO (660 4510);
DISPLAY INVISIBLE (660 4510);
FORCEPROP 1 LASTPIN (650 4500) BN 10
J 2
(700 4510);
DISPLAY 0.617021 (700 4510);
PAINT PINK (700 4510);
FORCEPROP 2 LAST CDS_LIB mstr_standard
J 0
(700 4500);
DISPLAY 0.787234 (700 4500);
PAINT MONO (700 4500);
DISPLAY INVISIBLE (700 4500);
FORCEPROP 1 LAST BODY_TYPE PLUMBING
J 2
(700 4450);
DISPLAY 1.234043 (700 4450);
PAINT GREEN (700 4450);
DISPLAY INVISIBLE (700 4450);
FORCEPROP 1 LAST HDL_TAP TRUE
J 2
(375 4375);
DISPLAY 1.234043 (375 4375);
PAINT GREEN (375 4375);
DISPLAY INVISIBLE (375 4375);
FORCEPROP 1 LAST PATH I24
J 2
(700 4500);
DISPLAY 0.936170 (700 4500);
PAINT GREEN (700 4500);
DISPLAY INVISIBLE (700 4500);
FORCEADD TAP..6
R 2
(700 4400);
FORCEPROP 3 LASTPIN (650 4400) SIG_NAME M_K_DQS_DP<9>
J 0
(660 4410);
DISPLAY 0.659574 (660 4410);
PAINT MONO (660 4410);
DISPLAY INVISIBLE (660 4410);
FORCEPROP 1 LASTPIN (650 4400) BN 9
J 2
(700 4410);
DISPLAY 0.617021 (700 4410);
PAINT PINK (700 4410);
FORCEPROP 2 LAST CDS_LIB mstr_standard
J 0
(700 4400);
DISPLAY 0.787234 (700 4400);
PAINT MONO (700 4400);
DISPLAY INVISIBLE (700 4400);
FORCEPROP 1 LAST BODY_TYPE PLUMBING
J 2
(700 4350);
DISPLAY 1.234043 (700 4350);
PAINT GREEN (700 4350);
DISPLAY INVISIBLE (700 4350);
FORCEPROP 1 LAST HDL_TAP TRUE
J 2
(375 4275);
DISPLAY 1.234043 (375 4275);
PAINT GREEN (375 4275);
DISPLAY INVISIBLE (375 4275);
FORCEPROP 1 LAST PATH I25
J 2
(700 4400);
DISPLAY 0.936170 (700 4400);
PAINT GREEN (700 4400);
DISPLAY INVISIBLE (700 4400);
FORCEADD TAP..6
R 2
(700 4100);
FORCEPROP 3 LASTPIN (650 4100) SIG_NAME M_K_DQS_DP<6>
J 0
(660 4110);
DISPLAY 0.659574 (660 4110);
PAINT MONO (660 4110);
DISPLAY INVISIBLE (660 4110);
FORCEPROP 1 LASTPIN (650 4100) BN 6
J 2
(700 4110);
DISPLAY 0.617021 (700 4110);
PAINT PINK (700 4110);
FORCEPROP 2 LAST CDS_LIB mstr_standard
J 0
(700 4100);
DISPLAY 0.787234 (700 4100);
PAINT MONO (700 4100);
DISPLAY INVISIBLE (700 4100);
FORCEPROP 1 LAST BODY_TYPE PLUMBING
J 2
(700 4050);
DISPLAY 1.234043 (700 4050);
PAINT GREEN (700 4050);
DISPLAY INVISIBLE (700 4050);
FORCEPROP 1 LAST HDL_TAP TRUE
J 2
(375 3975);
DISPLAY 1.234043 (375 3975);
PAINT GREEN (375 3975);
DISPLAY INVISIBLE (375 3975);
FORCEPROP 1 LAST PATH I26
J 2
(700 4100);
DISPLAY 0.936170 (700 4100);
PAINT GREEN (700 4100);
DISPLAY INVISIBLE (700 4100);
FORCEADD TAP..6
R 2
(700 4200);
FORCEPROP 3 LASTPIN (650 4200) SIG_NAME M_K_DQS_DP<7>
J 0
(660 4210);
DISPLAY 0.659574 (660 4210);
PAINT MONO (660 4210);
DISPLAY INVISIBLE (660 4210);
FORCEPROP 1 LASTPIN (650 4200) BN 7
J 2
(700 4210);
DISPLAY 0.617021 (700 4210);
PAINT PINK (700 4210);
FORCEPROP 2 LAST CDS_LIB mstr_standard
J 0
(700 4200);
DISPLAY 0.787234 (700 4200);
PAINT MONO (700 4200);
DISPLAY INVISIBLE (700 4200);
FORCEPROP 1 LAST BODY_TYPE PLUMBING
J 2
(700 4150);
DISPLAY 1.234043 (700 4150);
PAINT GREEN (700 4150);
DISPLAY INVISIBLE (700 4150);
FORCEPROP 1 LAST HDL_TAP TRUE
J 2
(375 4075);
DISPLAY 1.234043 (375 4075);
PAINT GREEN (375 4075);
DISPLAY INVISIBLE (375 4075);
FORCEPROP 1 LAST PATH I27
J 2
(700 4200);
DISPLAY 0.936170 (700 4200);
PAINT GREEN (700 4200);
DISPLAY INVISIBLE (700 4200);
FORCEADD TAP..6
R 2
(700 4300);
FORCEPROP 3 LASTPIN (650 4300) SIG_NAME M_K_DQS_DP<8>
J 0
(660 4310);
DISPLAY 0.659574 (660 4310);
PAINT MONO (660 4310);
DISPLAY INVISIBLE (660 4310);
FORCEPROP 1 LASTPIN (650 4300) BN 8
J 2
(700 4310);
DISPLAY 0.617021 (700 4310);
PAINT PINK (700 4310);
FORCEPROP 2 LAST CDS_LIB mstr_standard
J 0
(700 4300);
DISPLAY 0.787234 (700 4300);
PAINT MONO (700 4300);
DISPLAY INVISIBLE (700 4300);
FORCEPROP 1 LAST BODY_TYPE PLUMBING
J 2
(700 4250);
DISPLAY 1.234043 (700 4250);
PAINT GREEN (700 4250);
DISPLAY INVISIBLE (700 4250);
FORCEPROP 1 LAST HDL_TAP TRUE
J 2
(375 4175);
DISPLAY 1.234043 (375 4175);
PAINT GREEN (375 4175);
DISPLAY INVISIBLE (375 4175);
FORCEPROP 1 LAST PATH I28
J 2
(700 4300);
DISPLAY 0.936170 (700 4300);
PAINT GREEN (700 4300);
DISPLAY INVISIBLE (700 4300);
FORCEADD TAP..6
R 2
(900 4050);
FORCEPROP 3 LASTPIN (850 4050) SIG_NAME M_K_DQS_DN<6>
J 0
(860 4060);
DISPLAY 0.659574 (860 4060);
PAINT MONO (860 4060);
DISPLAY INVISIBLE (860 4060);
FORCEPROP 1 LASTPIN (850 4050) BN 6
J 2
(900 4060);
DISPLAY 0.617021 (900 4060);
PAINT PINK (900 4060);
FORCEPROP 2 LAST CDS_LIB mstr_standard
J 0
(900 4050);
DISPLAY 0.787234 (900 4050);
PAINT MONO (900 4050);
DISPLAY INVISIBLE (900 4050);
FORCEPROP 1 LAST BODY_TYPE PLUMBING
J 2
(900 4000);
DISPLAY 1.234043 (900 4000);
PAINT GREEN (900 4000);
DISPLAY INVISIBLE (900 4000);
FORCEPROP 1 LAST HDL_TAP TRUE
J 2
(575 3925);
DISPLAY 1.234043 (575 3925);
PAINT GREEN (575 3925);
DISPLAY INVISIBLE (575 3925);
FORCEPROP 1 LAST PATH I29
J 2
(900 4050);
DISPLAY 0.936170 (900 4050);
PAINT GREEN (900 4050);
DISPLAY INVISIBLE (900 4050);
FORCEADD TAP..6
R 2
(900 5150);
FORCEPROP 3 LASTPIN (850 5150) SIG_NAME M_K_DQS_DN<17>
J 0
(860 5160);
DISPLAY 0.659574 (860 5160);
PAINT MONO (860 5160);
DISPLAY INVISIBLE (860 5160);
FORCEPROP 1 LASTPIN (850 5150) BN 17
J 2
(900 5160);
DISPLAY 0.617021 (900 5160);
PAINT PINK (900 5160);
FORCEPROP 2 LAST CDS_LIB mstr_standard
J 2
(900 5150);
DISPLAY 0.787234 (900 5150);
PAINT MONO (900 5150);
DISPLAY INVISIBLE (900 5150);
FORCEPROP 1 LAST BODY_TYPE PLUMBING
J 2
(900 5100);
DISPLAY 1.234043 (900 5100);
PAINT GREEN (900 5100);
DISPLAY INVISIBLE (900 5100);
FORCEPROP 1 LAST HDL_TAP TRUE
J 2
(575 5025);
DISPLAY 1.234043 (575 5025);
PAINT GREEN (575 5025);
DISPLAY INVISIBLE (575 5025);
FORCEPROP 1 LAST PATH I3
J 2
(900 5150);
DISPLAY 0.936170 (900 5150);
PAINT GREEN (900 5150);
DISPLAY INVISIBLE (900 5150);
FORCEADD TAP..6
R 2
(900 3950);
FORCEPROP 3 LASTPIN (850 3950) SIG_NAME M_K_DQS_DN<5>
J 0
(860 3960);
DISPLAY 0.659574 (860 3960);
PAINT MONO (860 3960);
DISPLAY INVISIBLE (860 3960);
FORCEPROP 1 LASTPIN (850 3950) BN 5
J 2
(900 3960);
DISPLAY 0.617021 (900 3960);
PAINT PINK (900 3960);
FORCEPROP 2 LAST CDS_LIB mstr_standard
J 0
(900 3950);
DISPLAY 0.787234 (900 3950);
PAINT MONO (900 3950);
DISPLAY INVISIBLE (900 3950);
FORCEPROP 1 LAST BODY_TYPE PLUMBING
J 2
(900 3900);
DISPLAY 1.234043 (900 3900);
PAINT GREEN (900 3900);
DISPLAY INVISIBLE (900 3900);
FORCEPROP 1 LAST HDL_TAP TRUE
J 2
(575 3825);
DISPLAY 1.234043 (575 3825);
PAINT GREEN (575 3825);
DISPLAY INVISIBLE (575 3825);
FORCEPROP 1 LAST PATH I30
J 2
(900 3950);
DISPLAY 0.936170 (900 3950);
PAINT GREEN (900 3950);
DISPLAY INVISIBLE (900 3950);
FORCEADD TAP..6
R 2
(900 3850);
FORCEPROP 3 LASTPIN (850 3850) SIG_NAME M_K_DQS_DN<4>
J 0
(860 3860);
DISPLAY 0.659574 (860 3860);
PAINT MONO (860 3860);
DISPLAY INVISIBLE (860 3860);
FORCEPROP 1 LASTPIN (850 3850) BN 4
J 2
(900 3860);
DISPLAY 0.617021 (900 3860);
PAINT PINK (900 3860);
FORCEPROP 2 LAST CDS_LIB mstr_standard
J 0
(900 3850);
DISPLAY 0.787234 (900 3850);
PAINT MONO (900 3850);
DISPLAY INVISIBLE (900 3850);
FORCEPROP 1 LAST BODY_TYPE PLUMBING
J 2
(900 3800);
DISPLAY 1.234043 (900 3800);
PAINT GREEN (900 3800);
DISPLAY INVISIBLE (900 3800);
FORCEPROP 1 LAST HDL_TAP TRUE
J 2
(575 3725);
DISPLAY 1.234043 (575 3725);
PAINT GREEN (575 3725);
DISPLAY INVISIBLE (575 3725);
FORCEPROP 1 LAST PATH I31
J 2
(900 3850);
DISPLAY 0.936170 (900 3850);
PAINT GREEN (900 3850);
DISPLAY INVISIBLE (900 3850);
FORCEADD TAP..6
R 2
(900 3750);
FORCEPROP 3 LASTPIN (850 3750) SIG_NAME M_K_DQS_DN<3>
J 0
(860 3760);
DISPLAY 0.659574 (860 3760);
PAINT MONO (860 3760);
DISPLAY INVISIBLE (860 3760);
FORCEPROP 1 LASTPIN (850 3750) BN 3
J 2
(900 3760);
DISPLAY 0.617021 (900 3760);
PAINT PINK (900 3760);
FORCEPROP 2 LAST CDS_LIB mstr_standard
J 0
(900 3750);
DISPLAY 0.787234 (900 3750);
PAINT MONO (900 3750);
DISPLAY INVISIBLE (900 3750);
FORCEPROP 1 LAST BODY_TYPE PLUMBING
J 2
(900 3700);
DISPLAY 1.234043 (900 3700);
PAINT GREEN (900 3700);
DISPLAY INVISIBLE (900 3700);
FORCEPROP 1 LAST HDL_TAP TRUE
J 2
(575 3625);
DISPLAY 1.234043 (575 3625);
PAINT GREEN (575 3625);
DISPLAY INVISIBLE (575 3625);
FORCEPROP 1 LAST PATH I32
J 2
(900 3750);
DISPLAY 0.936170 (900 3750);
PAINT GREEN (900 3750);
DISPLAY INVISIBLE (900 3750);
FORCEADD TAP..6
R 2
(900 3650);
FORCEPROP 3 LASTPIN (850 3650) SIG_NAME M_K_DQS_DN<2>
J 0
(860 3660);
DISPLAY 0.659574 (860 3660);
PAINT MONO (860 3660);
DISPLAY INVISIBLE (860 3660);
FORCEPROP 1 LASTPIN (850 3650) BN 2
J 2
(900 3660);
DISPLAY 0.617021 (900 3660);
PAINT PINK (900 3660);
FORCEPROP 2 LAST CDS_LIB mstr_standard
J 0
(900 3650);
DISPLAY 0.787234 (900 3650);
PAINT MONO (900 3650);
DISPLAY INVISIBLE (900 3650);
FORCEPROP 1 LAST BODY_TYPE PLUMBING
J 2
(900 3600);
DISPLAY 1.234043 (900 3600);
PAINT GREEN (900 3600);
DISPLAY INVISIBLE (900 3600);
FORCEPROP 1 LAST HDL_TAP TRUE
J 2
(575 3525);
DISPLAY 1.234043 (575 3525);
PAINT GREEN (575 3525);
DISPLAY INVISIBLE (575 3525);
FORCEPROP 1 LAST PATH I33
J 2
(900 3650);
DISPLAY 0.936170 (900 3650);
PAINT GREEN (900 3650);
DISPLAY INVISIBLE (900 3650);
FORCEADD TAP..6
R 2
(700 4000);
FORCEPROP 3 LASTPIN (650 4000) SIG_NAME M_K_DQS_DP<5>
J 0
(660 4010);
DISPLAY 0.659574 (660 4010);
PAINT MONO (660 4010);
DISPLAY INVISIBLE (660 4010);
FORCEPROP 1 LASTPIN (650 4000) BN 5
J 2
(700 4010);
DISPLAY 0.617021 (700 4010);
PAINT PINK (700 4010);
FORCEPROP 2 LAST CDS_LIB mstr_standard
J 0
(700 4000);
DISPLAY 0.787234 (700 4000);
PAINT MONO (700 4000);
DISPLAY INVISIBLE (700 4000);
FORCEPROP 1 LAST BODY_TYPE PLUMBING
J 2
(700 3950);
DISPLAY 1.234043 (700 3950);
PAINT GREEN (700 3950);
DISPLAY INVISIBLE (700 3950);
FORCEPROP 1 LAST HDL_TAP TRUE
J 2
(375 3875);
DISPLAY 1.234043 (375 3875);
PAINT GREEN (375 3875);
DISPLAY INVISIBLE (375 3875);
FORCEPROP 1 LAST PATH I34
J 2
(700 4000);
DISPLAY 0.936170 (700 4000);
PAINT GREEN (700 4000);
DISPLAY INVISIBLE (700 4000);
FORCEADD TAP..6
R 2
(700 3900);
FORCEPROP 3 LASTPIN (650 3900) SIG_NAME M_K_DQS_DP<4>
J 0
(660 3910);
DISPLAY 0.659574 (660 3910);
PAINT MONO (660 3910);
DISPLAY INVISIBLE (660 3910);
FORCEPROP 1 LASTPIN (650 3900) BN 4
J 2
(700 3910);
DISPLAY 0.617021 (700 3910);
PAINT PINK (700 3910);
FORCEPROP 2 LAST CDS_LIB mstr_standard
J 0
(700 3900);
DISPLAY 0.787234 (700 3900);
PAINT MONO (700 3900);
DISPLAY INVISIBLE (700 3900);
FORCEPROP 1 LAST BODY_TYPE PLUMBING
J 2
(700 3850);
DISPLAY 1.234043 (700 3850);
PAINT GREEN (700 3850);
DISPLAY INVISIBLE (700 3850);
FORCEPROP 1 LAST HDL_TAP TRUE
J 2
(375 3775);
DISPLAY 1.234043 (375 3775);
PAINT GREEN (375 3775);
DISPLAY INVISIBLE (375 3775);
FORCEPROP 1 LAST PATH I35
J 2
(700 3900);
DISPLAY 0.936170 (700 3900);
PAINT GREEN (700 3900);
DISPLAY INVISIBLE (700 3900);
FORCEADD TAP..6
R 2
(700 3700);
FORCEPROP 3 LASTPIN (650 3700) SIG_NAME M_K_DQS_DP<2>
J 0
(660 3710);
DISPLAY 0.659574 (660 3710);
PAINT MONO (660 3710);
DISPLAY INVISIBLE (660 3710);
FORCEPROP 1 LASTPIN (650 3700) BN 2
J 2
(700 3710);
DISPLAY 0.617021 (700 3710);
PAINT PINK (700 3710);
FORCEPROP 2 LAST CDS_LIB mstr_standard
J 0
(700 3700);
DISPLAY 0.787234 (700 3700);
PAINT MONO (700 3700);
DISPLAY INVISIBLE (700 3700);
FORCEPROP 1 LAST BODY_TYPE PLUMBING
J 2
(700 3650);
DISPLAY 1.234043 (700 3650);
PAINT GREEN (700 3650);
DISPLAY INVISIBLE (700 3650);
FORCEPROP 1 LAST HDL_TAP TRUE
J 2
(375 3575);
DISPLAY 1.234043 (375 3575);
PAINT GREEN (375 3575);
DISPLAY INVISIBLE (375 3575);
FORCEPROP 1 LAST PATH I36
J 2
(700 3700);
DISPLAY 0.936170 (700 3700);
PAINT GREEN (700 3700);
DISPLAY INVISIBLE (700 3700);
FORCEADD TAP..6
R 2
(700 3600);
FORCEPROP 3 LASTPIN (650 3600) SIG_NAME M_K_DQS_DP<1>
J 0
(660 3610);
DISPLAY 0.659574 (660 3610);
PAINT MONO (660 3610);
DISPLAY INVISIBLE (660 3610);
FORCEPROP 1 LASTPIN (650 3600) BN 1
J 2
(700 3610);
DISPLAY 0.617021 (700 3610);
PAINT PINK (700 3610);
FORCEPROP 2 LAST CDS_LIB mstr_standard
J 0
(700 3600);
DISPLAY 0.787234 (700 3600);
PAINT MONO (700 3600);
DISPLAY INVISIBLE (700 3600);
FORCEPROP 1 LAST BODY_TYPE PLUMBING
J 2
(700 3550);
DISPLAY 1.234043 (700 3550);
PAINT GREEN (700 3550);
DISPLAY INVISIBLE (700 3550);
FORCEPROP 1 LAST HDL_TAP TRUE
J 2
(375 3475);
DISPLAY 1.234043 (375 3475);
PAINT GREEN (375 3475);
DISPLAY INVISIBLE (375 3475);
FORCEPROP 1 LAST PATH I37
J 2
(700 3600);
DISPLAY 0.936170 (700 3600);
PAINT GREEN (700 3600);
DISPLAY INVISIBLE (700 3600);
FORCEADD TAP..6
R 2
(700 3800);
FORCEPROP 3 LASTPIN (650 3800) SIG_NAME M_K_DQS_DP<3>
J 0
(660 3810);
DISPLAY 0.659574 (660 3810);
PAINT MONO (660 3810);
DISPLAY INVISIBLE (660 3810);
FORCEPROP 1 LASTPIN (650 3800) BN 3
J 2
(700 3810);
DISPLAY 0.617021 (700 3810);
PAINT PINK (700 3810);
FORCEPROP 2 LAST CDS_LIB mstr_standard
J 0
(700 3800);
DISPLAY 0.787234 (700 3800);
PAINT MONO (700 3800);
DISPLAY INVISIBLE (700 3800);
FORCEPROP 1 LAST BODY_TYPE PLUMBING
J 2
(700 3750);
DISPLAY 1.234043 (700 3750);
PAINT GREEN (700 3750);
DISPLAY INVISIBLE (700 3750);
FORCEPROP 1 LAST HDL_TAP TRUE
J 2
(375 3675);
DISPLAY 1.234043 (375 3675);
PAINT GREEN (375 3675);
DISPLAY INVISIBLE (375 3675);
FORCEPROP 1 LAST PATH I38
J 2
(700 3800);
DISPLAY 0.936170 (700 3800);
PAINT GREEN (700 3800);
DISPLAY INVISIBLE (700 3800);
FORCEADD TAP..6
R 2
(900 3450);
FORCEPROP 3 LASTPIN (850 3450) SIG_NAME M_K_DQS_DN<0>
J 0
(860 3460);
DISPLAY 0.659574 (860 3460);
PAINT MONO (860 3460);
DISPLAY INVISIBLE (860 3460);
FORCEPROP 1 LASTPIN (850 3450) BN 0
J 2
(900 3460);
DISPLAY 0.617021 (900 3460);
PAINT PINK (900 3460);
FORCEPROP 2 LAST CDS_LIB mstr_standard
J 0
(900 3450);
DISPLAY 0.787234 (900 3450);
PAINT MONO (900 3450);
DISPLAY INVISIBLE (900 3450);
FORCEPROP 1 LAST BODY_TYPE PLUMBING
J 2
(900 3400);
DISPLAY 1.234043 (900 3400);
PAINT GREEN (900 3400);
DISPLAY INVISIBLE (900 3400);
FORCEPROP 1 LAST HDL_TAP TRUE
J 2
(575 3325);
DISPLAY 1.234043 (575 3325);
PAINT GREEN (575 3325);
DISPLAY INVISIBLE (575 3325);
FORCEPROP 1 LAST PATH I39
J 2
(900 3450);
DISPLAY 0.936170 (900 3450);
PAINT GREEN (900 3450);
DISPLAY INVISIBLE (900 3450);
FORCEADD TAP..6
R 2
(700 5200);
FORCEPROP 3 LASTPIN (650 5200) SIG_NAME M_K_DQS_DP<17>
J 0
(660 5210);
DISPLAY 0.659574 (660 5210);
PAINT MONO (660 5210);
DISPLAY INVISIBLE (660 5210);
FORCEPROP 1 LASTPIN (650 5200) BN 17
J 2
(700 5210);
DISPLAY 0.617021 (700 5210);
PAINT PINK (700 5210);
FORCEPROP 2 LAST CDS_LIB mstr_standard
J 2
(700 5200);
DISPLAY 0.787234 (700 5200);
PAINT MONO (700 5200);
DISPLAY INVISIBLE (700 5200);
FORCEPROP 1 LAST BODY_TYPE PLUMBING
J 2
(700 5150);
DISPLAY 1.234043 (700 5150);
PAINT GREEN (700 5150);
DISPLAY INVISIBLE (700 5150);
FORCEPROP 1 LAST HDL_TAP TRUE
J 2
(375 5075);
DISPLAY 1.234043 (375 5075);
PAINT GREEN (375 5075);
DISPLAY INVISIBLE (375 5075);
FORCEPROP 1 LAST PATH I4
J 2
(700 5200);
DISPLAY 0.936170 (700 5200);
PAINT GREEN (700 5200);
DISPLAY INVISIBLE (700 5200);
FORCEADD TAP..6
R 2
(900 3550);
FORCEPROP 3 LASTPIN (850 3550) SIG_NAME M_K_DQS_DN<1>
J 0
(860 3560);
DISPLAY 0.659574 (860 3560);
PAINT MONO (860 3560);
DISPLAY INVISIBLE (860 3560);
FORCEPROP 1 LASTPIN (850 3550) BN 1
J 2
(900 3560);
DISPLAY 0.617021 (900 3560);
PAINT PINK (900 3560);
FORCEPROP 2 LAST CDS_LIB mstr_standard
J 0
(900 3550);
DISPLAY 0.787234 (900 3550);
PAINT MONO (900 3550);
DISPLAY INVISIBLE (900 3550);
FORCEPROP 1 LAST BODY_TYPE PLUMBING
J 2
(900 3500);
DISPLAY 1.234043 (900 3500);
PAINT GREEN (900 3500);
DISPLAY INVISIBLE (900 3500);
FORCEPROP 1 LAST HDL_TAP TRUE
J 2
(575 3425);
DISPLAY 1.234043 (575 3425);
PAINT GREEN (575 3425);
DISPLAY INVISIBLE (575 3425);
FORCEPROP 1 LAST PATH I40
J 2
(900 3550);
DISPLAY 0.936170 (900 3550);
PAINT GREEN (900 3550);
DISPLAY INVISIBLE (900 3550);
FORCEADD TAP..6
R 2
(700 3500);
FORCEPROP 3 LASTPIN (650 3500) SIG_NAME M_K_DQS_DP<0>
J 0
(660 3510);
DISPLAY 0.659574 (660 3510);
PAINT MONO (660 3510);
DISPLAY INVISIBLE (660 3510);
FORCEPROP 1 LASTPIN (650 3500) BN 0
J 2
(700 3510);
DISPLAY 0.617021 (700 3510);
PAINT PINK (700 3510);
FORCEPROP 2 LAST CDS_LIB mstr_standard
J 0
(700 3500);
DISPLAY 0.787234 (700 3500);
PAINT MONO (700 3500);
DISPLAY INVISIBLE (700 3500);
FORCEPROP 1 LAST BODY_TYPE PLUMBING
J 2
(700 3450);
DISPLAY 1.234043 (700 3450);
PAINT GREEN (700 3450);
DISPLAY INVISIBLE (700 3450);
FORCEPROP 1 LAST HDL_TAP TRUE
J 2
(375 3375);
DISPLAY 1.234043 (375 3375);
PAINT GREEN (375 3375);
DISPLAY INVISIBLE (375 3375);
FORCEPROP 1 LAST PATH I41
J 2
(700 3500);
DISPLAY 0.936170 (700 3500);
PAINT GREEN (700 3500);
DISPLAY INVISIBLE (700 3500);
FORCEADD SCONN288_H44441004..3
(1800 2400);
FORCEPROP 1 LAST LOCATION J1B1
J 0
(1350 3800);
DISPLAY 0.617021 (1350 3800);
PAINT AQUA (1350 3800);
FORCEPROP 1 LAST PART_NUMBER H44441-004
J 0
(1350 1050);
DISPLAY 0.617021 (1350 1050);
PAINT BLUE (1350 1050);
FORCEPROP 1 LAST MATERIAL SCONN
J 0
(1350 3750);
DISPLAY 0.617021 (1350 3750);
PAINT SKYBLUE (1350 3750);
FORCEPROP 2 LASTPIN (1300 3550) $PN 2
J 2
(1290 3560);
DISPLAY 0.617021 (1290 3560);
PAINT ORANGE (1290 3560);
FORCEPROP 2 LASTPIN (1300 3500) $PN 4
J 2
(1290 3510);
DISPLAY 0.617021 (1290 3510);
PAINT ORANGE (1290 3510);
FORCEPROP 2 LASTPIN (1300 3450) $PN 6
J 2
(1290 3460);
DISPLAY 0.617021 (1290 3460);
PAINT ORANGE (1290 3460);
FORCEPROP 2 LASTPIN (1300 3400) $PN 9
J 2
(1290 3410);
DISPLAY 0.617021 (1290 3410);
PAINT ORANGE (1290 3410);
FORCEPROP 2 LASTPIN (1300 3350) $PN 11
J 2
(1290 3360);
DISPLAY 0.617021 (1290 3360);
PAINT ORANGE (1290 3360);
FORCEPROP 2 LASTPIN (1300 3300) $PN 13
J 2
(1290 3310);
DISPLAY 0.617021 (1290 3310);
PAINT ORANGE (1290 3310);
FORCEPROP 2 LASTPIN (1300 3250) $PN 15
J 2
(1290 3260);
DISPLAY 0.617021 (1290 3260);
PAINT ORANGE (1290 3260);
FORCEPROP 2 LASTPIN (1300 3200) $PN 17
J 2
(1290 3210);
DISPLAY 0.617021 (1290 3210);
PAINT ORANGE (1290 3210);
FORCEPROP 2 LASTPIN (1300 3150) $PN 20
J 2
(1290 3160);
DISPLAY 0.617021 (1290 3160);
PAINT ORANGE (1290 3160);
FORCEPROP 2 LASTPIN (1300 3100) $PN 22
J 2
(1290 3110);
DISPLAY 0.617021 (1290 3110);
PAINT ORANGE (1290 3110);
FORCEPROP 2 LASTPIN (1300 3050) $PN 24
J 2
(1290 3060);
DISPLAY 0.617021 (1290 3060);
PAINT ORANGE (1290 3060);
FORCEPROP 2 LASTPIN (1300 3000) $PN 26
J 2
(1290 3010);
DISPLAY 0.617021 (1290 3010);
PAINT ORANGE (1290 3010);
FORCEPROP 2 LASTPIN (1300 2950) $PN 28
J 2
(1290 2960);
DISPLAY 0.617021 (1290 2960);
PAINT ORANGE (1290 2960);
FORCEPROP 2 LASTPIN (1300 2900) $PN 31
J 2
(1290 2910);
DISPLAY 0.617021 (1290 2910);
PAINT ORANGE (1290 2910);
FORCEPROP 2 LASTPIN (1300 2850) $PN 33
J 2
(1290 2860);
DISPLAY 0.617021 (1290 2860);
PAINT ORANGE (1290 2860);
FORCEPROP 2 LASTPIN (1300 2800) $PN 35
J 2
(1290 2810);
DISPLAY 0.617021 (1290 2810);
PAINT ORANGE (1290 2810);
FORCEPROP 2 LASTPIN (1300 2750) $PN 37
J 2
(1290 2760);
DISPLAY 0.617021 (1290 2760);
PAINT ORANGE (1290 2760);
FORCEPROP 2 LASTPIN (1300 2700) $PN 39
J 2
(1290 2710);
DISPLAY 0.617021 (1290 2710);
PAINT ORANGE (1290 2710);
FORCEPROP 2 LASTPIN (1300 2650) $PN 42
J 2
(1290 2660);
DISPLAY 0.617021 (1290 2660);
PAINT ORANGE (1290 2660);
FORCEPROP 2 LASTPIN (1300 2600) $PN 44
J 2
(1290 2610);
DISPLAY 0.617021 (1290 2610);
PAINT ORANGE (1290 2610);
FORCEPROP 2 LASTPIN (1300 2550) $PN 46
J 2
(1290 2560);
DISPLAY 0.617021 (1290 2560);
PAINT ORANGE (1290 2560);
FORCEPROP 2 LASTPIN (1300 2500) $PN 48
J 2
(1290 2510);
DISPLAY 0.617021 (1290 2510);
PAINT ORANGE (1290 2510);
FORCEPROP 2 LASTPIN (1300 2450) $PN 50
J 2
(1290 2460);
DISPLAY 0.617021 (1290 2460);
PAINT ORANGE (1290 2460);
FORCEPROP 2 LASTPIN (1300 2400) $PN 53
J 2
(1290 2410);
DISPLAY 0.617021 (1290 2410);
PAINT ORANGE (1290 2410);
FORCEPROP 2 LASTPIN (1300 2350) $PN 55
J 2
(1290 2360);
DISPLAY 0.617021 (1290 2360);
PAINT ORANGE (1290 2360);
FORCEPROP 2 LASTPIN (1300 2300) $PN 57
J 2
(1290 2310);
DISPLAY 0.617021 (1290 2310);
PAINT ORANGE (1290 2310);
FORCEPROP 2 LASTPIN (1300 2250) $PN 94
J 2
(1290 2260);
DISPLAY 0.617021 (1290 2260);
PAINT ORANGE (1290 2260);
FORCEPROP 2 LASTPIN (1300 2200) $PN 96
J 2
(1290 2210);
DISPLAY 0.617021 (1290 2210);
PAINT ORANGE (1290 2210);
FORCEPROP 2 LASTPIN (1300 2150) $PN 98
J 2
(1290 2160);
DISPLAY 0.617021 (1290 2160);
PAINT ORANGE (1290 2160);
FORCEPROP 2 LASTPIN (1300 2100) $PN 101
J 2
(1290 2110);
DISPLAY 0.617021 (1290 2110);
PAINT ORANGE (1290 2110);
FORCEPROP 2 LASTPIN (1300 2050) $PN 103
J 2
(1290 2060);
DISPLAY 0.617021 (1290 2060);
PAINT ORANGE (1290 2060);
FORCEPROP 2 LASTPIN (1300 1900) $PN 109
J 2
(1290 1910);
DISPLAY 0.617021 (1290 1910);
PAINT ORANGE (1290 1910);
FORCEPROP 2 LASTPIN (1300 1850) $PN 112
J 2
(1290 1860);
DISPLAY 0.617021 (1290 1860);
PAINT ORANGE (1290 1860);
FORCEPROP 2 LASTPIN (1300 1800) $PN 114
J 2
(1290 1810);
DISPLAY 0.617021 (1290 1810);
PAINT ORANGE (1290 1810);
FORCEPROP 2 LASTPIN (1300 1750) $PN 116
J 2
(1290 1760);
DISPLAY 0.617021 (1290 1760);
PAINT ORANGE (1290 1760);
FORCEPROP 2 LASTPIN (1300 1700) $PN 118
J 2
(1290 1710);
DISPLAY 0.617021 (1290 1710);
PAINT ORANGE (1290 1710);
FORCEPROP 2 LASTPIN (1300 1650) $PN 120
J 2
(1290 1660);
DISPLAY 0.617021 (1290 1660);
PAINT ORANGE (1290 1660);
FORCEPROP 2 LASTPIN (1300 1600) $PN 123
J 2
(1290 1610);
DISPLAY 0.617021 (1290 1610);
PAINT ORANGE (1290 1610);
FORCEPROP 2 LASTPIN (1300 1550) $PN 125
J 2
(1290 1560);
DISPLAY 0.617021 (1290 1560);
PAINT ORANGE (1290 1560);
FORCEPROP 2 LASTPIN (1300 1450) $PN 129
J 2
(1290 1460);
DISPLAY 0.617021 (1290 1460);
PAINT ORANGE (1290 1460);
FORCEPROP 2 LASTPIN (1300 1400) $PN 131
J 2
(1290 1410);
DISPLAY 0.617021 (1290 1410);
PAINT ORANGE (1290 1410);
FORCEPROP 2 LASTPIN (1300 1350) $PN 134
J 2
(1290 1360);
DISPLAY 0.617021 (1290 1360);
PAINT ORANGE (1290 1360);
FORCEPROP 2 LASTPIN (1300 1300) $PN 136
J 2
(1290 1310);
DISPLAY 0.617021 (1290 1310);
PAINT ORANGE (1290 1310);
FORCEPROP 2 LASTPIN (1300 1250) $PN 138
J 2
(1290 1260);
DISPLAY 0.617021 (1290 1260);
PAINT ORANGE (1290 1260);
FORCEPROP 2 LASTPIN (2300 3500) $PN 149
J 0
(2310 3510);
DISPLAY 0.617021 (2310 3510);
PAINT ORANGE (2310 3510);
FORCEPROP 2 LASTPIN (2300 3450) $PN 151
J 0
(2310 3460);
DISPLAY 0.617021 (2310 3460);
PAINT ORANGE (2310 3460);
FORCEPROP 2 LASTPIN (2300 3400) $PN 154
J 0
(2310 3410);
DISPLAY 0.617021 (2310 3410);
PAINT ORANGE (2310 3410);
FORCEPROP 2 LASTPIN (2300 3350) $PN 156
J 0
(2310 3360);
DISPLAY 0.617021 (2310 3360);
PAINT ORANGE (2310 3360);
FORCEPROP 2 LASTPIN (2300 3300) $PN 158
J 0
(2310 3310);
DISPLAY 0.617021 (2310 3310);
PAINT ORANGE (2310 3310);
FORCEPROP 2 LASTPIN (2300 3250) $PN 160
J 0
(2310 3260);
DISPLAY 0.617021 (2310 3260);
PAINT ORANGE (2310 3260);
FORCEPROP 2 LASTPIN (2300 3200) $PN 162
J 0
(2310 3210);
DISPLAY 0.617021 (2310 3210);
PAINT ORANGE (2310 3210);
FORCEPROP 2 LASTPIN (2300 3150) $PN 165
J 0
(2310 3160);
DISPLAY 0.617021 (2310 3160);
PAINT ORANGE (2310 3160);
FORCEPROP 2 LASTPIN (2300 3100) $PN 167
J 0
(2310 3110);
DISPLAY 0.617021 (2310 3110);
PAINT ORANGE (2310 3110);
FORCEPROP 2 LASTPIN (2300 3050) $PN 169
J 0
(2310 3060);
DISPLAY 0.617021 (2310 3060);
PAINT ORANGE (2310 3060);
FORCEPROP 2 LASTPIN (2300 3000) $PN 171
J 0
(2310 3010);
DISPLAY 0.617021 (2310 3010);
PAINT ORANGE (2310 3010);
FORCEPROP 2 LASTPIN (2300 2950) $PN 173
J 0
(2310 2960);
DISPLAY 0.617021 (2310 2960);
PAINT ORANGE (2310 2960);
FORCEPROP 2 LASTPIN (2300 2900) $PN 176
J 0
(2310 2910);
DISPLAY 0.617021 (2310 2910);
PAINT ORANGE (2310 2910);
FORCEPROP 2 LASTPIN (2300 2850) $PN 178
J 0
(2310 2860);
DISPLAY 0.617021 (2310 2860);
PAINT ORANGE (2310 2860);
FORCEPROP 2 LASTPIN (2300 2800) $PN 180
J 0
(2310 2810);
DISPLAY 0.617021 (2310 2810);
PAINT ORANGE (2310 2810);
FORCEPROP 2 LASTPIN (2300 2750) $PN 182
J 0
(2310 2760);
DISPLAY 0.617021 (2310 2760);
PAINT ORANGE (2310 2760);
FORCEPROP 2 LASTPIN (2300 2700) $PN 184
J 0
(2310 2710);
DISPLAY 0.617021 (2310 2710);
PAINT ORANGE (2310 2710);
FORCEPROP 2 LASTPIN (2300 2650) $PN 187
J 0
(2310 2660);
DISPLAY 0.617021 (2310 2660);
PAINT ORANGE (2310 2660);
FORCEPROP 2 LASTPIN (2300 2600) $PN 189
J 0
(2310 2610);
DISPLAY 0.617021 (2310 2610);
PAINT ORANGE (2310 2610);
FORCEPROP 2 LASTPIN (2300 2550) $PN 191
J 0
(2310 2560);
DISPLAY 0.617021 (2310 2560);
PAINT ORANGE (2310 2560);
FORCEPROP 2 LASTPIN (2300 2500) $PN 193
J 0
(2310 2510);
DISPLAY 0.617021 (2310 2510);
PAINT ORANGE (2310 2510);
FORCEPROP 2 LASTPIN (2300 2450) $PN 195
J 0
(2310 2460);
DISPLAY 0.617021 (2310 2460);
PAINT ORANGE (2310 2460);
FORCEPROP 2 LASTPIN (2300 2400) $PN 198
J 0
(2310 2410);
DISPLAY 0.617021 (2310 2410);
PAINT ORANGE (2310 2410);
FORCEPROP 2 LASTPIN (2300 2350) $PN 200
J 0
(2310 2360);
DISPLAY 0.617021 (2310 2360);
PAINT ORANGE (2310 2360);
FORCEPROP 2 LASTPIN (2300 2300) $PN 202
J 0
(2310 2310);
DISPLAY 0.617021 (2310 2310);
PAINT ORANGE (2310 2310);
FORCEPROP 2 LASTPIN (2300 2250) $PN 239
J 0
(2310 2260);
DISPLAY 0.617021 (2310 2260);
PAINT ORANGE (2310 2260);
FORCEPROP 2 LASTPIN (2300 2200) $PN 241
J 0
(2310 2210);
DISPLAY 0.617021 (2310 2210);
PAINT ORANGE (2310 2210);
FORCEPROP 2 LASTPIN (2300 2150) $PN 243
J 0
(2310 2160);
DISPLAY 0.617021 (2310 2160);
PAINT ORANGE (2310 2160);
FORCEPROP 2 LASTPIN (2300 2100) $PN 246
J 0
(2310 2110);
DISPLAY 0.617021 (2310 2110);
PAINT ORANGE (2310 2110);
FORCEPROP 2 LASTPIN (2300 2050) $PN 248
J 0
(2310 2060);
DISPLAY 0.617021 (2310 2060);
PAINT ORANGE (2310 2060);
FORCEPROP 2 LASTPIN (2300 2000) $PN 250
J 0
(2310 2010);
DISPLAY 0.617021 (2310 2010);
PAINT ORANGE (2310 2010);
FORCEPROP 2 LASTPIN (2300 1950) $PN 252
J 0
(2310 1960);
DISPLAY 0.617021 (2310 1960);
PAINT ORANGE (2310 1960);
FORCEPROP 2 LASTPIN (2300 1900) $PN 254
J 0
(2310 1910);
DISPLAY 0.617021 (2310 1910);
PAINT ORANGE (2310 1910);
FORCEPROP 2 LASTPIN (2300 1850) $PN 257
J 0
(2310 1860);
DISPLAY 0.617021 (2310 1860);
PAINT ORANGE (2310 1860);
FORCEPROP 2 LASTPIN (2300 1800) $PN 259
J 0
(2310 1810);
DISPLAY 0.617021 (2310 1810);
PAINT ORANGE (2310 1810);
FORCEPROP 2 LASTPIN (2300 1750) $PN 261
J 0
(2310 1760);
DISPLAY 0.617021 (2310 1760);
PAINT ORANGE (2310 1760);
FORCEPROP 2 LASTPIN (2300 1700) $PN 263
J 0
(2310 1710);
DISPLAY 0.617021 (2310 1710);
PAINT ORANGE (2310 1710);
FORCEPROP 2 LASTPIN (2300 1650) $PN 265
J 0
(2310 1660);
DISPLAY 0.617021 (2310 1660);
PAINT ORANGE (2310 1660);
FORCEPROP 2 LASTPIN (2300 1600) $PN 268
J 0
(2310 1610);
DISPLAY 0.617021 (2310 1610);
PAINT ORANGE (2310 1610);
FORCEPROP 2 LASTPIN (2300 1550) $PN 270
J 0
(2310 1560);
DISPLAY 0.617021 (2310 1560);
PAINT ORANGE (2310 1560);
FORCEPROP 2 LASTPIN (2300 1500) $PN 272
J 0
(2310 1510);
DISPLAY 0.617021 (2310 1510);
PAINT ORANGE (2310 1510);
FORCEPROP 2 LASTPIN (2300 1450) $PN 274
J 0
(2310 1460);
DISPLAY 0.617021 (2310 1460);
PAINT ORANGE (2310 1460);
FORCEPROP 2 LASTPIN (2300 1400) $PN 276
J 0
(2310 1410);
DISPLAY 0.617021 (2310 1410);
PAINT ORANGE (2310 1410);
FORCEPROP 2 LASTPIN (2300 1350) $PN 279
J 0
(2310 1360);
DISPLAY 0.617021 (2310 1360);
PAINT ORANGE (2310 1360);
FORCEPROP 2 LASTPIN (2300 1300) $PN 281
J 0
(2310 1310);
DISPLAY 0.617021 (2310 1310);
PAINT ORANGE (2310 1310);
FORCEPROP 2 LASTPIN (2300 1250) $PN 283
J 0
(2310 1260);
DISPLAY 0.617021 (2310 1260);
PAINT ORANGE (2310 1260);
FORCEPROP 2 LASTPIN (1300 1950) $PN 107
J 2
(1290 1960);
DISPLAY 0.617021 (1290 1960);
PAINT ORANGE (1290 1960);
FORCEPROP 2 LASTPIN (1300 2000) $PN 105
J 2
(1290 2010);
DISPLAY 0.617021 (1290 2010);
PAINT ORANGE (1290 2010);
FORCEPROP 2 LASTPIN (2300 3550) $PN 147
J 0
(2310 3560);
DISPLAY 0.617021 (2310 3560);
PAINT ORANGE (2310 3560);
FORCEPROP 2 LASTPIN (1300 1500) $PN 127
J 2
(1290 1510);
DISPLAY 0.617021 (1290 1510);
PAINT ORANGE (1290 1510);
FORCEPROP 1 LAST PACK_TYPE PIP
J 0
(1350 3850);
PAINT SKYBLUE (1350 3850);
DISPLAY INVISIBLE (1350 3850);
FORCEPROP 2 LAST BOM_COST MEM
J 0
(1800 2400);
PAINT ORANGE (1800 2400);
DISPLAY INVISIBLE (1800 2400);
FORCEPROP 2 LAST CDS_LIB mstr_sconn
J 0
(1800 2400);
PAINT ORANGE (1800 2400);
DISPLAY INVISIBLE (1800 2400);
FORCEPROP 2 LAST SEC_TYPE PIP
J 0
(1350 3850);
DISPLAY 1.021277 (1350 3850);
PAINT ORANGE (1350 3850);
DISPLAY INVISIBLE (1350 3850);
FORCEPROP 2 LAST SEC 3
J 0
(1350 3850);
DISPLAY 0.680851 (1350 3850);
PAINT MONO (1350 3850);
DISPLAY INVISIBLE (1350 3850);
FORCEPROP 2 LAST CDS_LOCATION J1B1
J 0
(1350 3800);
DISPLAY 0.617021 (1350 3800);
PAINT AQUA (1350 3800);
DISPLAY INVISIBLE (1350 3800);
FORCEPROP 1 LAST PATH I43
J 0
(1800 3750);
PAINT GREEN (1800 3750);
DISPLAY INVISIBLE (1800 3750);
FORCEPROP 2 LAST ROOM DDR4_CH_K
J 0
(1800 2400);
PAINT ORANGE (1800 2400);
DISPLAY INVISIBLE (1800 2400);
FORCEADD GND..1
R 2
(1100 1100);
FORCEPROP 3 LASTPIN (1100 1150) SIG_NAME GND\g
J 0
(1110 1160);
DISPLAY 0.659574 (1110 1160);
PAINT MONO (1110 1160);
DISPLAY INVISIBLE (1110 1160);
FORCEPROP 1 LAST VOLTAGE 0
J 0
(1100 1100);
PAINT SKYBLUE (1100 1100);
DISPLAY INVISIBLE (1100 1100);
FORCEPROP 2 LAST BOM_COST MEM
J 0
(1100 1105);
PAINT ORANGE (1100 1105);
DISPLAY INVISIBLE (1100 1105);
FORCEPROP 1 LAST SIZE 1B
J 2
(1025 1050);
DISPLAY 1.170213 (1025 1050);
PAINT GREEN (1025 1050);
DISPLAY INVISIBLE (1025 1050);
FORCEPROP 2 LAST CDS_LIB mstr_symbols
J 0
(1100 1100);
DISPLAY 0.787234 (1100 1100);
PAINT MONO (1100 1100);
DISPLAY INVISIBLE (1100 1100);
FORCEPROP 1 LAST BODY_TYPE PLUMBING
J 2
(1145 1057);
DISPLAY 0.340426 (1145 1057);
PAINT GREEN (1145 1057);
DISPLAY INVISIBLE (1145 1057);
FORCEPROP 1 LAST PATH I44
J 2
(1025 1100);
DISPLAY 0.936170 (1025 1100);
PAINT GREEN (1025 1100);
DISPLAY INVISIBLE (1025 1100);
FORCEPROP 2 LAST ROOM DDR4_CH_C
J 0
(1100 1105);
PAINT ORANGE (1100 1105);
DISPLAY INVISIBLE (1100 1105);
FORCEPROP 1 LAST HDL_POWER GND
J 2
(1100 1250);
DISPLAY 0.553191 (1100 1250);
PAINT GREEN (1100 1250);
DISPLAY INVISIBLE (1100 1250);
FORCEADD OFFPAGE..3
(-1100 4900);
FORCEPROP 2 LAST $XR1 84 
J 0
(-796 4900);
DISPLAY 0.638298 (-796 4900);
PAINT MONO (-796 4900);
FORCEPROP 2 LAST $XR0 60 
J 0
(-886 4900);
DISPLAY 0.638298 (-886 4900);
PAINT MONO (-886 4900);
FORCEPROP 2 LAST CDS_LIB mstr_standard
J 0
(-1100 4900);
DISPLAY 0.787234 (-1100 4900);
PAINT MONO (-1100 4900);
DISPLAY INVISIBLE (-1100 4900);
FORCEPROP 1 LAST OFFPAGE TRUE
J 0
(-775 4775);
DISPLAY 0.936170 (-775 4775);
PAINT GREEN (-775 4775);
DISPLAY INVISIBLE (-775 4775);
FORCEPROP 1 LAST COMMENT_BODY TRUE
J 0
(-1150 4800);
DISPLAY 0.936170 (-1150 4800);
PAINT GREEN (-1150 4800);
DISPLAY INVISIBLE (-1150 4800);
FORCEPROP 2 LAST PATH I45
J 0
(-900 4975);
DISPLAY 0.787234 (-900 4975);
PAINT MONO (-900 4975);
DISPLAY INVISIBLE (-900 4975);
FORCEADD TAP..6
R 2
(-1700 4750);
FORCEPROP 3 LASTPIN (-1750 4750) SIG_NAME M_K_DQ<60>
J 0
(-1740 4760);
DISPLAY 0.659574 (-1740 4760);
PAINT MONO (-1740 4760);
DISPLAY INVISIBLE (-1740 4760);
FORCEPROP 1 LASTPIN (-1750 4750) BN 60
J 2
(-1700 4760);
DISPLAY 0.617021 (-1700 4760);
PAINT PINK (-1700 4760);
FORCEPROP 2 LAST CDS_LIB mstr_standard
J 2
(-1700 4750);
DISPLAY 0.787234 (-1700 4750);
PAINT MONO (-1700 4750);
DISPLAY INVISIBLE (-1700 4750);
FORCEPROP 1 LAST BODY_TYPE PLUMBING
J 2
(-1700 4700);
DISPLAY 1.234043 (-1700 4700);
PAINT GREEN (-1700 4700);
DISPLAY INVISIBLE (-1700 4700);
FORCEPROP 1 LAST HDL_TAP TRUE
J 2
(-2025 4625);
DISPLAY 1.234043 (-2025 4625);
PAINT GREEN (-2025 4625);
DISPLAY INVISIBLE (-2025 4625);
FORCEPROP 1 LAST PATH I46
J 2
(-1700 4750);
DISPLAY 0.936170 (-1700 4750);
PAINT GREEN (-1700 4750);
DISPLAY INVISIBLE (-1700 4750);
FORCEADD TAP..6
R 2
(-1700 4700);
FORCEPROP 3 LASTPIN (-1750 4700) SIG_NAME M_K_DQ<61>
J 0
(-1740 4710);
DISPLAY 0.659574 (-1740 4710);
PAINT MONO (-1740 4710);
DISPLAY INVISIBLE (-1740 4710);
FORCEPROP 1 LASTPIN (-1750 4700) BN 61
J 2
(-1700 4710);
DISPLAY 0.617021 (-1700 4710);
PAINT PINK (-1700 4710);
FORCEPROP 2 LAST CDS_LIB mstr_standard
J 2
(-1700 4700);
DISPLAY 0.787234 (-1700 4700);
PAINT MONO (-1700 4700);
DISPLAY INVISIBLE (-1700 4700);
FORCEPROP 1 LAST BODY_TYPE PLUMBING
J 2
(-1700 4650);
DISPLAY 1.234043 (-1700 4650);
PAINT GREEN (-1700 4650);
DISPLAY INVISIBLE (-1700 4650);
FORCEPROP 1 LAST HDL_TAP TRUE
J 2
(-2025 4575);
DISPLAY 1.234043 (-2025 4575);
PAINT GREEN (-2025 4575);
DISPLAY INVISIBLE (-2025 4575);
FORCEPROP 1 LAST PATH I47
J 2
(-1700 4700);
DISPLAY 0.936170 (-1700 4700);
PAINT GREEN (-1700 4700);
DISPLAY INVISIBLE (-1700 4700);
FORCEADD TAP..6
R 2
(-1700 4800);
FORCEPROP 3 LASTPIN (-1750 4800) SIG_NAME M_K_DQ<63>
J 0
(-1740 4810);
DISPLAY 0.659574 (-1740 4810);
PAINT MONO (-1740 4810);
DISPLAY INVISIBLE (-1740 4810);
FORCEPROP 1 LASTPIN (-1750 4800) BN 63
J 2
(-1700 4810);
DISPLAY 0.617021 (-1700 4810);
PAINT PINK (-1700 4810);
FORCEPROP 2 LAST CDS_LIB mstr_standard
J 2
(-1700 4800);
DISPLAY 0.787234 (-1700 4800);
PAINT MONO (-1700 4800);
DISPLAY INVISIBLE (-1700 4800);
FORCEPROP 1 LAST BODY_TYPE PLUMBING
J 2
(-1700 4750);
DISPLAY 1.234043 (-1700 4750);
PAINT GREEN (-1700 4750);
DISPLAY INVISIBLE (-1700 4750);
FORCEPROP 1 LAST HDL_TAP TRUE
J 2
(-2025 4675);
DISPLAY 1.234043 (-2025 4675);
PAINT GREEN (-2025 4675);
DISPLAY INVISIBLE (-2025 4675);
FORCEPROP 1 LAST PATH I48
J 2
(-1700 4800);
DISPLAY 0.936170 (-1700 4800);
PAINT GREEN (-1700 4800);
DISPLAY INVISIBLE (-1700 4800);
FORCEADD TAP..6
R 2
(-1700 4850);
FORCEPROP 3 LASTPIN (-1750 4850) SIG_NAME M_K_DQ<62>
J 0
(-1740 4860);
DISPLAY 0.659574 (-1740 4860);
PAINT MONO (-1740 4860);
DISPLAY INVISIBLE (-1740 4860);
FORCEPROP 1 LASTPIN (-1750 4850) BN 62
J 2
(-1700 4860);
DISPLAY 0.617021 (-1700 4860);
PAINT PINK (-1700 4860);
FORCEPROP 2 LAST CDS_LIB mstr_standard
J 2
(-1700 4850);
DISPLAY 0.787234 (-1700 4850);
PAINT MONO (-1700 4850);
DISPLAY INVISIBLE (-1700 4850);
FORCEPROP 1 LAST BODY_TYPE PLUMBING
J 2
(-1700 4800);
DISPLAY 1.234043 (-1700 4800);
PAINT GREEN (-1700 4800);
DISPLAY INVISIBLE (-1700 4800);
FORCEPROP 1 LAST HDL_TAP TRUE
J 2
(-2025 4725);
DISPLAY 1.234043 (-2025 4725);
PAINT GREEN (-2025 4725);
DISPLAY INVISIBLE (-2025 4725);
FORCEPROP 1 LAST PATH I49
J 2
(-1700 4850);
DISPLAY 0.936170 (-1700 4850);
PAINT GREEN (-1700 4850);
DISPLAY INVISIBLE (-1700 4850);
FORCEADD TAP..6
R 2
(900 5050);
FORCEPROP 3 LASTPIN (850 5050) SIG_NAME M_K_DQS_DN<16>
J 0
(860 5060);
DISPLAY 0.659574 (860 5060);
PAINT MONO (860 5060);
DISPLAY INVISIBLE (860 5060);
FORCEPROP 1 LASTPIN (850 5050) BN 16
J 2
(900 5060);
DISPLAY 0.617021 (900 5060);
PAINT PINK (900 5060);
FORCEPROP 2 LAST CDS_LIB mstr_standard
J 0
(900 5050);
DISPLAY 0.787234 (900 5050);
PAINT MONO (900 5050);
DISPLAY INVISIBLE (900 5050);
FORCEPROP 1 LAST BODY_TYPE PLUMBING
J 2
(900 5000);
DISPLAY 1.234043 (900 5000);
PAINT GREEN (900 5000);
DISPLAY INVISIBLE (900 5000);
FORCEPROP 1 LAST HDL_TAP TRUE
J 2
(575 4925);
DISPLAY 1.234043 (575 4925);
PAINT GREEN (575 4925);
DISPLAY INVISIBLE (575 4925);
FORCEPROP 1 LAST PATH I5
J 2
(900 5050);
DISPLAY 0.936170 (900 5050);
PAINT GREEN (900 5050);
DISPLAY INVISIBLE (900 5050);
FORCEADD TAP..6
R 2
(-1700 4450);
FORCEPROP 3 LASTPIN (-1750 4450) SIG_NAME M_K_DQ<54>
J 0
(-1740 4460);
DISPLAY 0.659574 (-1740 4460);
PAINT MONO (-1740 4460);
DISPLAY INVISIBLE (-1740 4460);
FORCEPROP 1 LASTPIN (-1750 4450) BN 54
J 2
(-1700 4460);
DISPLAY 0.617021 (-1700 4460);
PAINT PINK (-1700 4460);
FORCEPROP 2 LAST CDS_LIB mstr_standard
J 2
(-1700 4450);
DISPLAY 0.787234 (-1700 4450);
PAINT MONO (-1700 4450);
DISPLAY INVISIBLE (-1700 4450);
FORCEPROP 1 LAST BODY_TYPE PLUMBING
J 2
(-1700 4400);
DISPLAY 1.234043 (-1700 4400);
PAINT GREEN (-1700 4400);
DISPLAY INVISIBLE (-1700 4400);
FORCEPROP 1 LAST HDL_TAP TRUE
J 2
(-2025 4325);
DISPLAY 1.234043 (-2025 4325);
PAINT GREEN (-2025 4325);
DISPLAY INVISIBLE (-2025 4325);
FORCEPROP 1 LAST PATH I50
J 2
(-1700 4450);
DISPLAY 0.936170 (-1700 4450);
PAINT GREEN (-1700 4450);
DISPLAY INVISIBLE (-1700 4450);
FORCEADD TAP..6
R 2
(-1700 4500);
FORCEPROP 3 LASTPIN (-1750 4500) SIG_NAME M_K_DQ<57>
J 0
(-1740 4510);
DISPLAY 0.659574 (-1740 4510);
PAINT MONO (-1740 4510);
DISPLAY INVISIBLE (-1740 4510);
FORCEPROP 1 LASTPIN (-1750 4500) BN 57
J 2
(-1700 4510);
DISPLAY 0.617021 (-1700 4510);
PAINT PINK (-1700 4510);
FORCEPROP 2 LAST CDS_LIB mstr_standard
J 2
(-1700 4500);
DISPLAY 0.787234 (-1700 4500);
PAINT MONO (-1700 4500);
DISPLAY INVISIBLE (-1700 4500);
FORCEPROP 1 LAST BODY_TYPE PLUMBING
J 2
(-1700 4450);
DISPLAY 1.234043 (-1700 4450);
PAINT GREEN (-1700 4450);
DISPLAY INVISIBLE (-1700 4450);
FORCEPROP 1 LAST HDL_TAP TRUE
J 2
(-2025 4375);
DISPLAY 1.234043 (-2025 4375);
PAINT GREEN (-2025 4375);
DISPLAY INVISIBLE (-2025 4375);
FORCEPROP 1 LAST PATH I51
J 2
(-1700 4500);
DISPLAY 0.936170 (-1700 4500);
PAINT GREEN (-1700 4500);
DISPLAY INVISIBLE (-1700 4500);
FORCEADD TAP..6
R 2
(-1700 4600);
FORCEPROP 3 LASTPIN (-1750 4600) SIG_NAME M_K_DQ<59>
J 0
(-1740 4610);
DISPLAY 0.659574 (-1740 4610);
PAINT MONO (-1740 4610);
DISPLAY INVISIBLE (-1740 4610);
FORCEPROP 1 LASTPIN (-1750 4600) BN 59
J 2
(-1700 4610);
DISPLAY 0.617021 (-1700 4610);
PAINT PINK (-1700 4610);
FORCEPROP 2 LAST CDS_LIB mstr_standard
J 2
(-1700 4600);
DISPLAY 0.787234 (-1700 4600);
PAINT MONO (-1700 4600);
DISPLAY INVISIBLE (-1700 4600);
FORCEPROP 1 LAST BODY_TYPE PLUMBING
J 2
(-1700 4550);
DISPLAY 1.234043 (-1700 4550);
PAINT GREEN (-1700 4550);
DISPLAY INVISIBLE (-1700 4550);
FORCEPROP 1 LAST HDL_TAP TRUE
J 2
(-2025 4475);
DISPLAY 1.234043 (-2025 4475);
PAINT GREEN (-2025 4475);
DISPLAY INVISIBLE (-2025 4475);
FORCEPROP 1 LAST PATH I52
J 2
(-1700 4600);
DISPLAY 0.936170 (-1700 4600);
PAINT GREEN (-1700 4600);
DISPLAY INVISIBLE (-1700 4600);
FORCEADD TAP..6
R 2
(-1700 4550);
FORCEPROP 3 LASTPIN (-1750 4550) SIG_NAME M_K_DQ<56>
J 0
(-1740 4560);
DISPLAY 0.659574 (-1740 4560);
PAINT MONO (-1740 4560);
DISPLAY INVISIBLE (-1740 4560);
FORCEPROP 1 LASTPIN (-1750 4550) BN 56
J 2
(-1700 4560);
DISPLAY 0.617021 (-1700 4560);
PAINT PINK (-1700 4560);
FORCEPROP 2 LAST CDS_LIB mstr_standard
J 2
(-1700 4550);
DISPLAY 0.787234 (-1700 4550);
PAINT MONO (-1700 4550);
DISPLAY INVISIBLE (-1700 4550);
FORCEPROP 1 LAST BODY_TYPE PLUMBING
J 2
(-1700 4500);
DISPLAY 1.234043 (-1700 4500);
PAINT GREEN (-1700 4500);
DISPLAY INVISIBLE (-1700 4500);
FORCEPROP 1 LAST HDL_TAP TRUE
J 2
(-2025 4425);
DISPLAY 1.234043 (-2025 4425);
PAINT GREEN (-2025 4425);
DISPLAY INVISIBLE (-2025 4425);
FORCEPROP 1 LAST PATH I53
J 2
(-1700 4550);
DISPLAY 0.936170 (-1700 4550);
PAINT GREEN (-1700 4550);
DISPLAY INVISIBLE (-1700 4550);
FORCEADD TAP..6
R 2
(-1700 4650);
FORCEPROP 3 LASTPIN (-1750 4650) SIG_NAME M_K_DQ<58>
J 0
(-1740 4660);
DISPLAY 0.659574 (-1740 4660);
PAINT MONO (-1740 4660);
DISPLAY INVISIBLE (-1740 4660);
FORCEPROP 1 LASTPIN (-1750 4650) BN 58
J 2
(-1700 4660);
DISPLAY 0.617021 (-1700 4660);
PAINT PINK (-1700 4660);
FORCEPROP 2 LAST CDS_LIB mstr_standard
J 2
(-1700 4650);
DISPLAY 0.787234 (-1700 4650);
PAINT MONO (-1700 4650);
DISPLAY INVISIBLE (-1700 4650);
FORCEPROP 1 LAST BODY_TYPE PLUMBING
J 2
(-1700 4600);
DISPLAY 1.234043 (-1700 4600);
PAINT GREEN (-1700 4600);
DISPLAY INVISIBLE (-1700 4600);
FORCEPROP 1 LAST HDL_TAP TRUE
J 2
(-2025 4525);
DISPLAY 1.234043 (-2025 4525);
PAINT GREEN (-2025 4525);
DISPLAY INVISIBLE (-2025 4525);
FORCEPROP 1 LAST PATH I54
J 2
(-1700 4650);
DISPLAY 0.936170 (-1700 4650);
PAINT GREEN (-1700 4650);
DISPLAY INVISIBLE (-1700 4650);
FORCEADD TAP..6
R 2
(-1700 4200);
FORCEPROP 3 LASTPIN (-1750 4200) SIG_NAME M_K_DQ<51>
J 0
(-1740 4210);
DISPLAY 0.659574 (-1740 4210);
PAINT MONO (-1740 4210);
DISPLAY INVISIBLE (-1740 4210);
FORCEPROP 1 LASTPIN (-1750 4200) BN 51
J 2
(-1700 4210);
DISPLAY 0.617021 (-1700 4210);
PAINT PINK (-1700 4210);
FORCEPROP 2 LAST CDS_LIB mstr_standard
J 2
(-1700 4200);
DISPLAY 0.787234 (-1700 4200);
PAINT MONO (-1700 4200);
DISPLAY INVISIBLE (-1700 4200);
FORCEPROP 1 LAST BODY_TYPE PLUMBING
J 2
(-1700 4150);
DISPLAY 1.234043 (-1700 4150);
PAINT GREEN (-1700 4150);
DISPLAY INVISIBLE (-1700 4150);
FORCEPROP 1 LAST HDL_TAP TRUE
J 2
(-2025 4075);
DISPLAY 1.234043 (-2025 4075);
PAINT GREEN (-2025 4075);
DISPLAY INVISIBLE (-2025 4075);
FORCEPROP 1 LAST PATH I55
J 2
(-1700 4200);
DISPLAY 0.936170 (-1700 4200);
PAINT GREEN (-1700 4200);
DISPLAY INVISIBLE (-1700 4200);
FORCEADD TAP..6
R 2
(-1700 4250);
FORCEPROP 3 LASTPIN (-1750 4250) SIG_NAME M_K_DQ<50>
J 0
(-1740 4260);
DISPLAY 0.659574 (-1740 4260);
PAINT MONO (-1740 4260);
DISPLAY INVISIBLE (-1740 4260);
FORCEPROP 1 LASTPIN (-1750 4250) BN 50
J 2
(-1700 4260);
DISPLAY 0.617021 (-1700 4260);
PAINT PINK (-1700 4260);
FORCEPROP 2 LAST CDS_LIB mstr_standard
J 2
(-1700 4250);
DISPLAY 0.787234 (-1700 4250);
PAINT MONO (-1700 4250);
DISPLAY INVISIBLE (-1700 4250);
FORCEPROP 1 LAST BODY_TYPE PLUMBING
J 2
(-1700 4200);
DISPLAY 1.234043 (-1700 4200);
PAINT GREEN (-1700 4200);
DISPLAY INVISIBLE (-1700 4200);
FORCEPROP 1 LAST HDL_TAP TRUE
J 2
(-2025 4125);
DISPLAY 1.234043 (-2025 4125);
PAINT GREEN (-2025 4125);
DISPLAY INVISIBLE (-2025 4125);
FORCEPROP 1 LAST PATH I56
J 2
(-1700 4250);
DISPLAY 0.936170 (-1700 4250);
PAINT GREEN (-1700 4250);
DISPLAY INVISIBLE (-1700 4250);
FORCEADD TAP..6
R 2
(-1700 4300);
FORCEPROP 3 LASTPIN (-1750 4300) SIG_NAME M_K_DQ<53>
J 0
(-1740 4310);
DISPLAY 0.659574 (-1740 4310);
PAINT MONO (-1740 4310);
DISPLAY INVISIBLE (-1740 4310);
FORCEPROP 1 LASTPIN (-1750 4300) BN 53
J 2
(-1700 4310);
DISPLAY 0.617021 (-1700 4310);
PAINT PINK (-1700 4310);
FORCEPROP 2 LAST CDS_LIB mstr_standard
J 2
(-1700 4300);
DISPLAY 0.787234 (-1700 4300);
PAINT MONO (-1700 4300);
DISPLAY INVISIBLE (-1700 4300);
FORCEPROP 1 LAST BODY_TYPE PLUMBING
J 2
(-1700 4250);
DISPLAY 1.234043 (-1700 4250);
PAINT GREEN (-1700 4250);
DISPLAY INVISIBLE (-1700 4250);
FORCEPROP 1 LAST HDL_TAP TRUE
J 2
(-2025 4175);
DISPLAY 1.234043 (-2025 4175);
PAINT GREEN (-2025 4175);
DISPLAY INVISIBLE (-2025 4175);
FORCEPROP 1 LAST PATH I57
J 2
(-1700 4300);
DISPLAY 0.936170 (-1700 4300);
PAINT GREEN (-1700 4300);
DISPLAY INVISIBLE (-1700 4300);
FORCEADD TAP..6
R 2
(-1700 4400);
FORCEPROP 3 LASTPIN (-1750 4400) SIG_NAME M_K_DQ<55>
J 0
(-1740 4410);
DISPLAY 0.659574 (-1740 4410);
PAINT MONO (-1740 4410);
DISPLAY INVISIBLE (-1740 4410);
FORCEPROP 1 LASTPIN (-1750 4400) BN 55
J 2
(-1700 4410);
DISPLAY 0.617021 (-1700 4410);
PAINT PINK (-1700 4410);
FORCEPROP 2 LAST CDS_LIB mstr_standard
J 2
(-1700 4400);
DISPLAY 0.787234 (-1700 4400);
PAINT MONO (-1700 4400);
DISPLAY INVISIBLE (-1700 4400);
FORCEPROP 1 LAST BODY_TYPE PLUMBING
J 2
(-1700 4350);
DISPLAY 1.234043 (-1700 4350);
PAINT GREEN (-1700 4350);
DISPLAY INVISIBLE (-1700 4350);
FORCEPROP 1 LAST HDL_TAP TRUE
J 2
(-2025 4275);
DISPLAY 1.234043 (-2025 4275);
PAINT GREEN (-2025 4275);
DISPLAY INVISIBLE (-2025 4275);
FORCEPROP 1 LAST PATH I58
J 2
(-1700 4400);
DISPLAY 0.936170 (-1700 4400);
PAINT GREEN (-1700 4400);
DISPLAY INVISIBLE (-1700 4400);
FORCEADD TAP..6
R 2
(-1700 4350);
FORCEPROP 3 LASTPIN (-1750 4350) SIG_NAME M_K_DQ<52>
J 0
(-1740 4360);
DISPLAY 0.659574 (-1740 4360);
PAINT MONO (-1740 4360);
DISPLAY INVISIBLE (-1740 4360);
FORCEPROP 1 LASTPIN (-1750 4350) BN 52
J 2
(-1700 4360);
DISPLAY 0.617021 (-1700 4360);
PAINT PINK (-1700 4360);
FORCEPROP 2 LAST CDS_LIB mstr_standard
J 2
(-1700 4350);
DISPLAY 0.787234 (-1700 4350);
PAINT MONO (-1700 4350);
DISPLAY INVISIBLE (-1700 4350);
FORCEPROP 1 LAST BODY_TYPE PLUMBING
J 2
(-1700 4300);
DISPLAY 1.234043 (-1700 4300);
PAINT GREEN (-1700 4300);
DISPLAY INVISIBLE (-1700 4300);
FORCEPROP 1 LAST HDL_TAP TRUE
J 2
(-2025 4225);
DISPLAY 1.234043 (-2025 4225);
PAINT GREEN (-2025 4225);
DISPLAY INVISIBLE (-2025 4225);
FORCEPROP 1 LAST PATH I59
J 2
(-1700 4350);
DISPLAY 0.936170 (-1700 4350);
PAINT GREEN (-1700 4350);
DISPLAY INVISIBLE (-1700 4350);
FORCEADD TAP..6
R 2
(900 4950);
FORCEPROP 3 LASTPIN (850 4950) SIG_NAME M_K_DQS_DN<15>
J 0
(860 4960);
DISPLAY 0.659574 (860 4960);
PAINT MONO (860 4960);
DISPLAY INVISIBLE (860 4960);
FORCEPROP 1 LASTPIN (850 4950) BN 15
J 2
(900 4960);
DISPLAY 0.617021 (900 4960);
PAINT PINK (900 4960);
FORCEPROP 2 LAST CDS_LIB mstr_standard
J 0
(900 4950);
DISPLAY 0.787234 (900 4950);
PAINT MONO (900 4950);
DISPLAY INVISIBLE (900 4950);
FORCEPROP 1 LAST BODY_TYPE PLUMBING
J 2
(900 4900);
DISPLAY 1.234043 (900 4900);
PAINT GREEN (900 4900);
DISPLAY INVISIBLE (900 4900);
FORCEPROP 1 LAST HDL_TAP TRUE
J 2
(575 4825);
DISPLAY 1.234043 (575 4825);
PAINT GREEN (575 4825);
DISPLAY INVISIBLE (575 4825);
FORCEPROP 1 LAST PATH I6
J 2
(900 4950);
DISPLAY 0.936170 (900 4950);
PAINT GREEN (900 4950);
DISPLAY INVISIBLE (900 4950);
FORCEADD TAP..6
R 2
(-1700 3900);
FORCEPROP 3 LASTPIN (-1750 3900) SIG_NAME M_K_DQ<45>
J 0
(-1740 3910);
DISPLAY 0.659574 (-1740 3910);
PAINT MONO (-1740 3910);
DISPLAY INVISIBLE (-1740 3910);
FORCEPROP 1 LASTPIN (-1750 3900) BN 45
J 2
(-1700 3910);
DISPLAY 0.617021 (-1700 3910);
PAINT PINK (-1700 3910);
FORCEPROP 2 LAST CDS_LIB mstr_standard
J 2
(-1700 3900);
DISPLAY 0.787234 (-1700 3900);
PAINT MONO (-1700 3900);
DISPLAY INVISIBLE (-1700 3900);
FORCEPROP 1 LAST BODY_TYPE PLUMBING
J 2
(-1700 3850);
DISPLAY 1.234043 (-1700 3850);
PAINT GREEN (-1700 3850);
DISPLAY INVISIBLE (-1700 3850);
FORCEPROP 1 LAST HDL_TAP TRUE
J 2
(-2025 3775);
DISPLAY 1.234043 (-2025 3775);
PAINT GREEN (-2025 3775);
DISPLAY INVISIBLE (-2025 3775);
FORCEPROP 1 LAST PATH I60
J 2
(-1700 3900);
DISPLAY 0.936170 (-1700 3900);
PAINT GREEN (-1700 3900);
DISPLAY INVISIBLE (-1700 3900);
FORCEADD TAP..6
R 2
(-1700 3950);
FORCEPROP 3 LASTPIN (-1750 3950) SIG_NAME M_K_DQ<44>
J 0
(-1740 3960);
DISPLAY 0.659574 (-1740 3960);
PAINT MONO (-1740 3960);
DISPLAY INVISIBLE (-1740 3960);
FORCEPROP 1 LASTPIN (-1750 3950) BN 44
J 2
(-1700 3960);
DISPLAY 0.617021 (-1700 3960);
PAINT PINK (-1700 3960);
FORCEPROP 2 LAST CDS_LIB mstr_standard
J 2
(-1700 3950);
DISPLAY 0.787234 (-1700 3950);
PAINT MONO (-1700 3950);
DISPLAY INVISIBLE (-1700 3950);
FORCEPROP 1 LAST BODY_TYPE PLUMBING
J 2
(-1700 3900);
DISPLAY 1.234043 (-1700 3900);
PAINT GREEN (-1700 3900);
DISPLAY INVISIBLE (-1700 3900);
FORCEPROP 1 LAST HDL_TAP TRUE
J 2
(-2025 3825);
DISPLAY 1.234043 (-2025 3825);
PAINT GREEN (-2025 3825);
DISPLAY INVISIBLE (-2025 3825);
FORCEPROP 1 LAST PATH I61
J 2
(-1700 3950);
DISPLAY 0.936170 (-1700 3950);
PAINT GREEN (-1700 3950);
DISPLAY INVISIBLE (-1700 3950);
FORCEADD TAP..6
R 2
(-1700 4000);
FORCEPROP 3 LASTPIN (-1750 4000) SIG_NAME M_K_DQ<47>
J 0
(-1740 4010);
DISPLAY 0.659574 (-1740 4010);
PAINT MONO (-1740 4010);
DISPLAY INVISIBLE (-1740 4010);
FORCEPROP 1 LASTPIN (-1750 4000) BN 47
J 2
(-1700 4010);
DISPLAY 0.617021 (-1700 4010);
PAINT PINK (-1700 4010);
FORCEPROP 2 LAST CDS_LIB mstr_standard
J 2
(-1700 4000);
DISPLAY 0.787234 (-1700 4000);
PAINT MONO (-1700 4000);
DISPLAY INVISIBLE (-1700 4000);
FORCEPROP 1 LAST BODY_TYPE PLUMBING
J 2
(-1700 3950);
DISPLAY 1.234043 (-1700 3950);
PAINT GREEN (-1700 3950);
DISPLAY INVISIBLE (-1700 3950);
FORCEPROP 1 LAST HDL_TAP TRUE
J 2
(-2025 3875);
DISPLAY 1.234043 (-2025 3875);
PAINT GREEN (-2025 3875);
DISPLAY INVISIBLE (-2025 3875);
FORCEPROP 1 LAST PATH I62
J 2
(-1700 4000);
DISPLAY 0.936170 (-1700 4000);
PAINT GREEN (-1700 4000);
DISPLAY INVISIBLE (-1700 4000);
FORCEADD TAP..6
R 2
(-1700 4100);
FORCEPROP 3 LASTPIN (-1750 4100) SIG_NAME M_K_DQ<49>
J 0
(-1740 4110);
DISPLAY 0.659574 (-1740 4110);
PAINT MONO (-1740 4110);
DISPLAY INVISIBLE (-1740 4110);
FORCEPROP 1 LASTPIN (-1750 4100) BN 49
J 2
(-1700 4110);
DISPLAY 0.617021 (-1700 4110);
PAINT PINK (-1700 4110);
FORCEPROP 2 LAST CDS_LIB mstr_standard
J 2
(-1700 4100);
DISPLAY 0.787234 (-1700 4100);
PAINT MONO (-1700 4100);
DISPLAY INVISIBLE (-1700 4100);
FORCEPROP 1 LAST BODY_TYPE PLUMBING
J 2
(-1700 4050);
DISPLAY 1.234043 (-1700 4050);
PAINT GREEN (-1700 4050);
DISPLAY INVISIBLE (-1700 4050);
FORCEPROP 1 LAST HDL_TAP TRUE
J 2
(-2025 3975);
DISPLAY 1.234043 (-2025 3975);
PAINT GREEN (-2025 3975);
DISPLAY INVISIBLE (-2025 3975);
FORCEPROP 1 LAST PATH I63
J 2
(-1700 4100);
DISPLAY 0.936170 (-1700 4100);
PAINT GREEN (-1700 4100);
DISPLAY INVISIBLE (-1700 4100);
FORCEADD TAP..6
R 2
(-1700 4050);
FORCEPROP 3 LASTPIN (-1750 4050) SIG_NAME M_K_DQ<46>
J 0
(-1740 4060);
DISPLAY 0.659574 (-1740 4060);
PAINT MONO (-1740 4060);
DISPLAY INVISIBLE (-1740 4060);
FORCEPROP 1 LASTPIN (-1750 4050) BN 46
J 2
(-1700 4060);
DISPLAY 0.617021 (-1700 4060);
PAINT PINK (-1700 4060);
FORCEPROP 2 LAST CDS_LIB mstr_standard
J 2
(-1700 4050);
DISPLAY 0.787234 (-1700 4050);
PAINT MONO (-1700 4050);
DISPLAY INVISIBLE (-1700 4050);
FORCEPROP 1 LAST BODY_TYPE PLUMBING
J 2
(-1700 4000);
DISPLAY 1.234043 (-1700 4000);
PAINT GREEN (-1700 4000);
DISPLAY INVISIBLE (-1700 4000);
FORCEPROP 1 LAST HDL_TAP TRUE
J 2
(-2025 3925);
DISPLAY 1.234043 (-2025 3925);
PAINT GREEN (-2025 3925);
DISPLAY INVISIBLE (-2025 3925);
FORCEPROP 1 LAST PATH I64
J 2
(-1700 4050);
DISPLAY 0.936170 (-1700 4050);
PAINT GREEN (-1700 4050);
DISPLAY INVISIBLE (-1700 4050);
FORCEADD TAP..6
R 2
(-1700 4150);
FORCEPROP 3 LASTPIN (-1750 4150) SIG_NAME M_K_DQ<48>
J 0
(-1740 4160);
DISPLAY 0.659574 (-1740 4160);
PAINT MONO (-1740 4160);
DISPLAY INVISIBLE (-1740 4160);
FORCEPROP 1 LASTPIN (-1750 4150) BN 48
J 2
(-1700 4160);
DISPLAY 0.617021 (-1700 4160);
PAINT PINK (-1700 4160);
FORCEPROP 2 LAST CDS_LIB mstr_standard
J 2
(-1700 4150);
DISPLAY 0.787234 (-1700 4150);
PAINT MONO (-1700 4150);
DISPLAY INVISIBLE (-1700 4150);
FORCEPROP 1 LAST BODY_TYPE PLUMBING
J 2
(-1700 4100);
DISPLAY 1.234043 (-1700 4100);
PAINT GREEN (-1700 4100);
DISPLAY INVISIBLE (-1700 4100);
FORCEPROP 1 LAST HDL_TAP TRUE
J 2
(-2025 4025);
DISPLAY 1.234043 (-2025 4025);
PAINT GREEN (-2025 4025);
DISPLAY INVISIBLE (-2025 4025);
FORCEPROP 1 LAST PATH I65
J 2
(-1700 4150);
DISPLAY 0.936170 (-1700 4150);
PAINT GREEN (-1700 4150);
DISPLAY INVISIBLE (-1700 4150);
FORCEADD SCONN288_H44441004..2
(0 4350);
FORCEPROP 1 LAST LOCATION J1B1
J 0
(-400 5450);
DISPLAY 0.617021 (-400 5450);
PAINT AQUA (-400 5450);
FORCEPROP 1 LAST PART_NUMBER H44441-004
J 0
(-400 3250);
DISPLAY 0.617021 (-400 3250);
PAINT BLUE (-400 3250);
FORCEPROP 1 LAST MATERIAL SCONN
J 0
(-400 5400);
DISPLAY 0.617021 (-400 5400);
PAINT SKYBLUE (-400 5400);
FORCEPROP 2 LASTPIN (450 5200) $PN 51
J 0
(460 5210);
DISPLAY 0.617021 (460 5210);
PAINT ORANGE (460 5210);
FORCEPROP 2 LASTPIN (450 5150) $PN 52
J 0
(460 5160);
DISPLAY 0.617021 (460 5160);
PAINT ORANGE (460 5160);
FORCEPROP 2 LASTPIN (450 5100) $PN 132
J 0
(460 5110);
DISPLAY 0.617021 (460 5110);
PAINT ORANGE (460 5110);
FORCEPROP 2 LASTPIN (450 5050) $PN 133
J 0
(460 5060);
DISPLAY 0.617021 (460 5060);
PAINT ORANGE (460 5060);
FORCEPROP 2 LASTPIN (450 5000) $PN 121
J 0
(460 5010);
DISPLAY 0.617021 (460 5010);
PAINT ORANGE (460 5010);
FORCEPROP 2 LASTPIN (450 4950) $PN 122
J 0
(460 4960);
DISPLAY 0.617021 (460 4960);
PAINT ORANGE (460 4960);
FORCEPROP 2 LASTPIN (450 4900) $PN 110
J 0
(460 4910);
DISPLAY 0.617021 (460 4910);
PAINT ORANGE (460 4910);
FORCEPROP 2 LASTPIN (450 4850) $PN 111
J 0
(460 4860);
DISPLAY 0.617021 (460 4860);
PAINT ORANGE (460 4860);
FORCEPROP 2 LASTPIN (450 4800) $PN 99
J 0
(460 4810);
DISPLAY 0.617021 (460 4810);
PAINT ORANGE (460 4810);
FORCEPROP 2 LASTPIN (450 4750) $PN 100
J 0
(460 4760);
DISPLAY 0.617021 (460 4760);
PAINT ORANGE (460 4760);
FORCEPROP 2 LASTPIN (450 4700) $PN 40
J 0
(460 4710);
DISPLAY 0.617021 (460 4710);
PAINT ORANGE (460 4710);
FORCEPROP 2 LASTPIN (450 4650) $PN 41
J 0
(460 4660);
DISPLAY 0.617021 (460 4660);
PAINT ORANGE (460 4660);
FORCEPROP 2 LASTPIN (450 4600) $PN 29
J 0
(460 4610);
DISPLAY 0.617021 (460 4610);
PAINT ORANGE (460 4610);
FORCEPROP 2 LASTPIN (450 4550) $PN 30
J 0
(460 4560);
DISPLAY 0.617021 (460 4560);
PAINT ORANGE (460 4560);
FORCEPROP 2 LASTPIN (450 4500) $PN 18
J 0
(460 4510);
DISPLAY 0.617021 (460 4510);
PAINT ORANGE (460 4510);
FORCEPROP 2 LASTPIN (450 4450) $PN 19
J 0
(460 4460);
DISPLAY 0.617021 (460 4460);
PAINT ORANGE (460 4460);
FORCEPROP 2 LASTPIN (450 4400) $PN 7
J 0
(460 4410);
DISPLAY 0.617021 (460 4410);
PAINT ORANGE (460 4410);
FORCEPROP 2 LASTPIN (450 4350) $PN 8
J 0
(460 4360);
DISPLAY 0.617021 (460 4360);
PAINT ORANGE (460 4360);
FORCEPROP 2 LASTPIN (450 4300) $PN 197
J 0
(460 4310);
DISPLAY 0.617021 (460 4310);
PAINT ORANGE (460 4310);
FORCEPROP 2 LASTPIN (450 4200) $PN 278
J 0
(460 4210);
DISPLAY 0.617021 (460 4210);
PAINT ORANGE (460 4210);
FORCEPROP 2 LASTPIN (450 4150) $PN 277
J 0
(460 4160);
DISPLAY 0.617021 (460 4160);
PAINT ORANGE (460 4160);
FORCEPROP 2 LASTPIN (450 4100) $PN 267
J 0
(460 4110);
DISPLAY 0.617021 (460 4110);
PAINT ORANGE (460 4110);
FORCEPROP 2 LASTPIN (450 4050) $PN 266
J 0
(460 4060);
DISPLAY 0.617021 (460 4060);
PAINT ORANGE (460 4060);
FORCEPROP 2 LASTPIN (450 4000) $PN 256
J 0
(460 4010);
DISPLAY 0.617021 (460 4010);
PAINT ORANGE (460 4010);
FORCEPROP 2 LASTPIN (450 3950) $PN 255
J 0
(460 3960);
DISPLAY 0.617021 (460 3960);
PAINT ORANGE (460 3960);
FORCEPROP 2 LASTPIN (450 3900) $PN 245
J 0
(460 3910);
DISPLAY 0.617021 (460 3910);
PAINT ORANGE (460 3910);
FORCEPROP 2 LASTPIN (450 3850) $PN 244
J 0
(460 3860);
DISPLAY 0.617021 (460 3860);
PAINT ORANGE (460 3860);
FORCEPROP 2 LASTPIN (450 3800) $PN 186
J 0
(460 3810);
DISPLAY 0.617021 (460 3810);
PAINT ORANGE (460 3810);
FORCEPROP 2 LASTPIN (450 3750) $PN 185
J 0
(460 3760);
DISPLAY 0.617021 (460 3760);
PAINT ORANGE (460 3760);
FORCEPROP 2 LASTPIN (450 3700) $PN 175
J 0
(460 3710);
DISPLAY 0.617021 (460 3710);
PAINT ORANGE (460 3710);
FORCEPROP 2 LASTPIN (450 3650) $PN 174
J 0
(460 3660);
DISPLAY 0.617021 (460 3660);
PAINT ORANGE (460 3660);
FORCEPROP 2 LASTPIN (450 3600) $PN 164
J 0
(460 3610);
DISPLAY 0.617021 (460 3610);
PAINT ORANGE (460 3610);
FORCEPROP 2 LASTPIN (450 3550) $PN 163
J 0
(460 3560);
DISPLAY 0.617021 (460 3560);
PAINT ORANGE (460 3560);
FORCEPROP 2 LASTPIN (450 3500) $PN 153
J 0
(460 3510);
DISPLAY 0.617021 (460 3510);
PAINT ORANGE (460 3510);
FORCEPROP 2 LASTPIN (450 3450) $PN 152
J 0
(460 3460);
DISPLAY 0.617021 (460 3460);
PAINT ORANGE (460 3460);
FORCEPROP 2 LASTPIN (450 4250) $PN 196
J 0
(460 4260);
DISPLAY 0.617021 (460 4260);
PAINT ORANGE (460 4260);
FORCEPROP 1 LAST PACK_TYPE PIP
J 0
(-400 5500);
PAINT SKYBLUE (-400 5500);
DISPLAY INVISIBLE (-400 5500);
FORCEPROP 2 LAST BOM_COST MEM
J 0
(0 4350);
PAINT ORANGE (0 4350);
DISPLAY INVISIBLE (0 4350);
FORCEPROP 2 LAST CDS_LIB mstr_sconn
J 0
(0 4350);
PAINT ORANGE (0 4350);
DISPLAY INVISIBLE (0 4350);
FORCEPROP 2 LAST SEC_TYPE PIP
J 0
(-400 5500);
DISPLAY 1.021277 (-400 5500);
PAINT ORANGE (-400 5500);
DISPLAY INVISIBLE (-400 5500);
FORCEPROP 2 LAST SEC 2
J 0
(-400 5500);
DISPLAY 0.680851 (-400 5500);
PAINT MONO (-400 5500);
DISPLAY INVISIBLE (-400 5500);
FORCEPROP 2 LAST CDS_LOCATION J1B1
J 0
(-400 5450);
DISPLAY 0.617021 (-400 5450);
PAINT AQUA (-400 5450);
DISPLAY INVISIBLE (-400 5450);
FORCEPROP 1 LAST PATH I66
J 0
(0 5400);
PAINT GREEN (0 5400);
DISPLAY INVISIBLE (0 5400);
FORCEPROP 2 LAST ROOM DDR4_CH_K
J 0
(-400 5550);
PAINT ORANGE (-400 5550);
DISPLAY INVISIBLE (-400 5550);
FORCEADD TAP..6
R 2
(-1700 3750);
FORCEPROP 3 LASTPIN (-1750 3750) SIG_NAME M_K_DQ<40>
J 0
(-1740 3760);
DISPLAY 0.659574 (-1740 3760);
PAINT MONO (-1740 3760);
DISPLAY INVISIBLE (-1740 3760);
FORCEPROP 1 LASTPIN (-1750 3750) BN 40
J 2
(-1700 3760);
DISPLAY 0.617021 (-1700 3760);
PAINT PINK (-1700 3760);
FORCEPROP 2 LAST CDS_LIB mstr_standard
J 2
(-1700 3750);
DISPLAY 0.787234 (-1700 3750);
PAINT MONO (-1700 3750);
DISPLAY INVISIBLE (-1700 3750);
FORCEPROP 1 LAST BODY_TYPE PLUMBING
J 2
(-1700 3700);
DISPLAY 1.234043 (-1700 3700);
PAINT GREEN (-1700 3700);
DISPLAY INVISIBLE (-1700 3700);
FORCEPROP 1 LAST HDL_TAP TRUE
J 2
(-2025 3625);
DISPLAY 1.234043 (-2025 3625);
PAINT GREEN (-2025 3625);
DISPLAY INVISIBLE (-2025 3625);
FORCEPROP 1 LAST PATH I67
J 2
(-1700 3750);
DISPLAY 0.936170 (-1700 3750);
PAINT GREEN (-1700 3750);
DISPLAY INVISIBLE (-1700 3750);
FORCEADD TAP..6
R 2
(-1700 3650);
FORCEPROP 3 LASTPIN (-1750 3650) SIG_NAME M_K_DQ<38>
J 0
(-1740 3660);
DISPLAY 0.659574 (-1740 3660);
PAINT MONO (-1740 3660);
DISPLAY INVISIBLE (-1740 3660);
FORCEPROP 1 LASTPIN (-1750 3650) BN 38
J 2
(-1700 3660);
DISPLAY 0.617021 (-1700 3660);
PAINT PINK (-1700 3660);
FORCEPROP 2 LAST CDS_LIB mstr_standard
J 2
(-1700 3650);
DISPLAY 0.787234 (-1700 3650);
PAINT MONO (-1700 3650);
DISPLAY INVISIBLE (-1700 3650);
FORCEPROP 1 LAST BODY_TYPE PLUMBING
J 2
(-1700 3600);
DISPLAY 1.234043 (-1700 3600);
PAINT GREEN (-1700 3600);
DISPLAY INVISIBLE (-1700 3600);
FORCEPROP 1 LAST HDL_TAP TRUE
J 2
(-2025 3525);
DISPLAY 1.234043 (-2025 3525);
PAINT GREEN (-2025 3525);
DISPLAY INVISIBLE (-2025 3525);
FORCEPROP 1 LAST PATH I68
J 2
(-1700 3650);
DISPLAY 0.936170 (-1700 3650);
PAINT GREEN (-1700 3650);
DISPLAY INVISIBLE (-1700 3650);
FORCEADD TAP..6
R 2
(-1700 3700);
FORCEPROP 3 LASTPIN (-1750 3700) SIG_NAME M_K_DQ<41>
J 0
(-1740 3710);
DISPLAY 0.659574 (-1740 3710);
PAINT MONO (-1740 3710);
DISPLAY INVISIBLE (-1740 3710);
FORCEPROP 1 LASTPIN (-1750 3700) BN 41
J 2
(-1700 3710);
DISPLAY 0.617021 (-1700 3710);
PAINT PINK (-1700 3710);
FORCEPROP 2 LAST CDS_LIB mstr_standard
J 2
(-1700 3700);
DISPLAY 0.787234 (-1700 3700);
PAINT MONO (-1700 3700);
DISPLAY INVISIBLE (-1700 3700);
FORCEPROP 1 LAST BODY_TYPE PLUMBING
J 2
(-1700 3650);
DISPLAY 1.234043 (-1700 3650);
PAINT GREEN (-1700 3650);
DISPLAY INVISIBLE (-1700 3650);
FORCEPROP 1 LAST HDL_TAP TRUE
J 2
(-2025 3575);
DISPLAY 1.234043 (-2025 3575);
PAINT GREEN (-2025 3575);
DISPLAY INVISIBLE (-2025 3575);
FORCEPROP 1 LAST PATH I69
J 2
(-1700 3700);
DISPLAY 0.936170 (-1700 3700);
PAINT GREEN (-1700 3700);
DISPLAY INVISIBLE (-1700 3700);
FORCEADD TAP..6
R 2
(900 4850);
FORCEPROP 3 LASTPIN (850 4850) SIG_NAME M_K_DQS_DN<14>
J 0
(860 4860);
DISPLAY 0.659574 (860 4860);
PAINT MONO (860 4860);
DISPLAY INVISIBLE (860 4860);
FORCEPROP 1 LASTPIN (850 4850) BN 14
J 2
(900 4860);
DISPLAY 0.617021 (900 4860);
PAINT PINK (900 4860);
FORCEPROP 2 LAST CDS_LIB mstr_standard
J 0
(900 4850);
DISPLAY 0.787234 (900 4850);
PAINT MONO (900 4850);
DISPLAY INVISIBLE (900 4850);
FORCEPROP 1 LAST BODY_TYPE PLUMBING
J 2
(900 4800);
DISPLAY 1.234043 (900 4800);
PAINT GREEN (900 4800);
DISPLAY INVISIBLE (900 4800);
FORCEPROP 1 LAST HDL_TAP TRUE
J 2
(575 4725);
DISPLAY 1.234043 (575 4725);
PAINT GREEN (575 4725);
DISPLAY INVISIBLE (575 4725);
FORCEPROP 1 LAST PATH I7
J 2
(900 4850);
DISPLAY 0.936170 (900 4850);
PAINT GREEN (900 4850);
DISPLAY INVISIBLE (900 4850);
FORCEADD TAP..6
R 2
(-1700 3800);
FORCEPROP 3 LASTPIN (-1750 3800) SIG_NAME M_K_DQ<43>
J 0
(-1740 3810);
DISPLAY 0.659574 (-1740 3810);
PAINT MONO (-1740 3810);
DISPLAY INVISIBLE (-1740 3810);
FORCEPROP 1 LASTPIN (-1750 3800) BN 43
J 2
(-1700 3810);
DISPLAY 0.617021 (-1700 3810);
PAINT PINK (-1700 3810);
FORCEPROP 2 LAST CDS_LIB mstr_standard
J 2
(-1700 3800);
DISPLAY 0.787234 (-1700 3800);
PAINT MONO (-1700 3800);
DISPLAY INVISIBLE (-1700 3800);
FORCEPROP 1 LAST BODY_TYPE PLUMBING
J 2
(-1700 3750);
DISPLAY 1.234043 (-1700 3750);
PAINT GREEN (-1700 3750);
DISPLAY INVISIBLE (-1700 3750);
FORCEPROP 1 LAST HDL_TAP TRUE
J 2
(-2025 3675);
DISPLAY 1.234043 (-2025 3675);
PAINT GREEN (-2025 3675);
DISPLAY INVISIBLE (-2025 3675);
FORCEPROP 1 LAST PATH I70
J 2
(-1700 3800);
DISPLAY 0.936170 (-1700 3800);
PAINT GREEN (-1700 3800);
DISPLAY INVISIBLE (-1700 3800);
FORCEADD TAP..6
R 2
(-1700 3850);
FORCEPROP 3 LASTPIN (-1750 3850) SIG_NAME M_K_DQ<42>
J 0
(-1740 3860);
DISPLAY 0.659574 (-1740 3860);
PAINT MONO (-1740 3860);
DISPLAY INVISIBLE (-1740 3860);
FORCEPROP 1 LASTPIN (-1750 3850) BN 42
J 2
(-1700 3860);
DISPLAY 0.617021 (-1700 3860);
PAINT PINK (-1700 3860);
FORCEPROP 2 LAST CDS_LIB mstr_standard
J 2
(-1700 3850);
DISPLAY 0.787234 (-1700 3850);
PAINT MONO (-1700 3850);
DISPLAY INVISIBLE (-1700 3850);
FORCEPROP 1 LAST BODY_TYPE PLUMBING
J 2
(-1700 3800);
DISPLAY 1.234043 (-1700 3800);
PAINT GREEN (-1700 3800);
DISPLAY INVISIBLE (-1700 3800);
FORCEPROP 1 LAST HDL_TAP TRUE
J 2
(-2025 3725);
DISPLAY 1.234043 (-2025 3725);
PAINT GREEN (-2025 3725);
DISPLAY INVISIBLE (-2025 3725);
FORCEPROP 1 LAST PATH I71
J 2
(-1700 3850);
DISPLAY 0.936170 (-1700 3850);
PAINT GREEN (-1700 3850);
DISPLAY INVISIBLE (-1700 3850);
FORCEADD TAP..6
R 2
(-1700 3450);
FORCEPROP 3 LASTPIN (-1750 3450) SIG_NAME M_K_DQ<34>
J 0
(-1740 3460);
DISPLAY 0.659574 (-1740 3460);
PAINT MONO (-1740 3460);
DISPLAY INVISIBLE (-1740 3460);
FORCEPROP 1 LASTPIN (-1750 3450) BN 34
J 2
(-1700 3460);
DISPLAY 0.617021 (-1700 3460);
PAINT PINK (-1700 3460);
FORCEPROP 2 LAST CDS_LIB mstr_standard
J 2
(-1700 3450);
DISPLAY 0.787234 (-1700 3450);
PAINT MONO (-1700 3450);
DISPLAY INVISIBLE (-1700 3450);
FORCEPROP 1 LAST BODY_TYPE PLUMBING
J 2
(-1700 3400);
DISPLAY 1.234043 (-1700 3400);
PAINT GREEN (-1700 3400);
DISPLAY INVISIBLE (-1700 3400);
FORCEPROP 1 LAST HDL_TAP TRUE
J 2
(-2025 3325);
DISPLAY 1.234043 (-2025 3325);
PAINT GREEN (-2025 3325);
DISPLAY INVISIBLE (-2025 3325);
FORCEPROP 1 LAST PATH I72
J 2
(-1700 3450);
DISPLAY 0.936170 (-1700 3450);
PAINT GREEN (-1700 3450);
DISPLAY INVISIBLE (-1700 3450);
FORCEADD TAP..6
R 2
(-1700 3400);
FORCEPROP 3 LASTPIN (-1750 3400) SIG_NAME M_K_DQ<35>
J 0
(-1740 3410);
DISPLAY 0.659574 (-1740 3410);
PAINT MONO (-1740 3410);
DISPLAY INVISIBLE (-1740 3410);
FORCEPROP 1 LASTPIN (-1750 3400) BN 35
J 2
(-1700 3410);
DISPLAY 0.617021 (-1700 3410);
PAINT PINK (-1700 3410);
FORCEPROP 2 LAST CDS_LIB mstr_standard
J 2
(-1700 3400);
DISPLAY 0.787234 (-1700 3400);
PAINT MONO (-1700 3400);
DISPLAY INVISIBLE (-1700 3400);
FORCEPROP 1 LAST BODY_TYPE PLUMBING
J 2
(-1700 3350);
DISPLAY 1.234043 (-1700 3350);
PAINT GREEN (-1700 3350);
DISPLAY INVISIBLE (-1700 3350);
FORCEPROP 1 LAST HDL_TAP TRUE
J 2
(-2025 3275);
DISPLAY 1.234043 (-2025 3275);
PAINT GREEN (-2025 3275);
DISPLAY INVISIBLE (-2025 3275);
FORCEPROP 1 LAST PATH I73
J 2
(-1700 3400);
DISPLAY 0.936170 (-1700 3400);
PAINT GREEN (-1700 3400);
DISPLAY INVISIBLE (-1700 3400);
FORCEADD TAP..6
R 2
(-1700 3500);
FORCEPROP 3 LASTPIN (-1750 3500) SIG_NAME M_K_DQ<37>
J 0
(-1740 3510);
DISPLAY 0.659574 (-1740 3510);
PAINT MONO (-1740 3510);
DISPLAY INVISIBLE (-1740 3510);
FORCEPROP 1 LASTPIN (-1750 3500) BN 37
J 2
(-1700 3510);
DISPLAY 0.617021 (-1700 3510);
PAINT PINK (-1700 3510);
FORCEPROP 2 LAST CDS_LIB mstr_standard
J 2
(-1700 3500);
DISPLAY 0.787234 (-1700 3500);
PAINT MONO (-1700 3500);
DISPLAY INVISIBLE (-1700 3500);
FORCEPROP 1 LAST BODY_TYPE PLUMBING
J 2
(-1700 3450);
DISPLAY 1.234043 (-1700 3450);
PAINT GREEN (-1700 3450);
DISPLAY INVISIBLE (-1700 3450);
FORCEPROP 1 LAST HDL_TAP TRUE
J 2
(-2025 3375);
DISPLAY 1.234043 (-2025 3375);
PAINT GREEN (-2025 3375);
DISPLAY INVISIBLE (-2025 3375);
FORCEPROP 1 LAST PATH I74
J 2
(-1700 3500);
DISPLAY 0.936170 (-1700 3500);
PAINT GREEN (-1700 3500);
DISPLAY INVISIBLE (-1700 3500);
FORCEADD TAP..6
R 2
(-1700 3550);
FORCEPROP 3 LASTPIN (-1750 3550) SIG_NAME M_K_DQ<36>
J 0
(-1740 3560);
DISPLAY 0.659574 (-1740 3560);
PAINT MONO (-1740 3560);
DISPLAY INVISIBLE (-1740 3560);
FORCEPROP 1 LASTPIN (-1750 3550) BN 36
J 2
(-1700 3560);
DISPLAY 0.617021 (-1700 3560);
PAINT PINK (-1700 3560);
FORCEPROP 2 LAST CDS_LIB mstr_standard
J 2
(-1700 3550);
DISPLAY 0.787234 (-1700 3550);
PAINT MONO (-1700 3550);
DISPLAY INVISIBLE (-1700 3550);
FORCEPROP 1 LAST BODY_TYPE PLUMBING
J 2
(-1700 3500);
DISPLAY 1.234043 (-1700 3500);
PAINT GREEN (-1700 3500);
DISPLAY INVISIBLE (-1700 3500);
FORCEPROP 1 LAST HDL_TAP TRUE
J 2
(-2025 3425);
DISPLAY 1.234043 (-2025 3425);
PAINT GREEN (-2025 3425);
DISPLAY INVISIBLE (-2025 3425);
FORCEPROP 1 LAST PATH I75
J 2
(-1700 3550);
DISPLAY 0.936170 (-1700 3550);
PAINT GREEN (-1700 3550);
DISPLAY INVISIBLE (-1700 3550);
FORCEADD TAP..6
R 2
(-1700 3600);
FORCEPROP 3 LASTPIN (-1750 3600) SIG_NAME M_K_DQ<39>
J 0
(-1740 3610);
DISPLAY 0.659574 (-1740 3610);
PAINT MONO (-1740 3610);
DISPLAY INVISIBLE (-1740 3610);
FORCEPROP 1 LASTPIN (-1750 3600) BN 39
J 2
(-1700 3610);
DISPLAY 0.617021 (-1700 3610);
PAINT PINK (-1700 3610);
FORCEPROP 2 LAST CDS_LIB mstr_standard
J 2
(-1700 3600);
DISPLAY 0.787234 (-1700 3600);
PAINT MONO (-1700 3600);
DISPLAY INVISIBLE (-1700 3600);
FORCEPROP 1 LAST BODY_TYPE PLUMBING
J 2
(-1700 3550);
DISPLAY 1.234043 (-1700 3550);
PAINT GREEN (-1700 3550);
DISPLAY INVISIBLE (-1700 3550);
FORCEPROP 1 LAST HDL_TAP TRUE
J 2
(-2025 3475);
DISPLAY 1.234043 (-2025 3475);
PAINT GREEN (-2025 3475);
DISPLAY INVISIBLE (-2025 3475);
FORCEPROP 1 LAST PATH I76
J 2
(-1700 3600);
DISPLAY 0.936170 (-1700 3600);
PAINT GREEN (-1700 3600);
DISPLAY INVISIBLE (-1700 3600);
FORCEADD TAP..6
R 2
(-1700 3200);
FORCEPROP 3 LASTPIN (-1750 3200) SIG_NAME M_K_DQ<31>
J 0
(-1740 3210);
DISPLAY 0.659574 (-1740 3210);
PAINT MONO (-1740 3210);
DISPLAY INVISIBLE (-1740 3210);
FORCEPROP 1 LASTPIN (-1750 3200) BN 31
J 2
(-1700 3210);
DISPLAY 0.617021 (-1700 3210);
PAINT PINK (-1700 3210);
FORCEPROP 2 LAST CDS_LIB mstr_standard
J 2
(-1700 3200);
DISPLAY 0.787234 (-1700 3200);
PAINT MONO (-1700 3200);
DISPLAY INVISIBLE (-1700 3200);
FORCEPROP 1 LAST BODY_TYPE PLUMBING
J 2
(-1700 3150);
DISPLAY 1.234043 (-1700 3150);
PAINT GREEN (-1700 3150);
DISPLAY INVISIBLE (-1700 3150);
FORCEPROP 1 LAST HDL_TAP TRUE
J 2
(-2025 3075);
DISPLAY 1.234043 (-2025 3075);
PAINT GREEN (-2025 3075);
DISPLAY INVISIBLE (-2025 3075);
FORCEPROP 1 LAST PATH I77
J 2
(-1700 3200);
DISPLAY 0.936170 (-1700 3200);
PAINT GREEN (-1700 3200);
DISPLAY INVISIBLE (-1700 3200);
FORCEADD TAP..6
R 2
(-1700 3250);
FORCEPROP 3 LASTPIN (-1750 3250) SIG_NAME M_K_DQ<30>
J 0
(-1740 3260);
DISPLAY 0.659574 (-1740 3260);
PAINT MONO (-1740 3260);
DISPLAY INVISIBLE (-1740 3260);
FORCEPROP 1 LASTPIN (-1750 3250) BN 30
J 2
(-1700 3260);
DISPLAY 0.617021 (-1700 3260);
PAINT PINK (-1700 3260);
FORCEPROP 2 LAST CDS_LIB mstr_standard
J 2
(-1700 3250);
DISPLAY 0.787234 (-1700 3250);
PAINT MONO (-1700 3250);
DISPLAY INVISIBLE (-1700 3250);
FORCEPROP 1 LAST BODY_TYPE PLUMBING
J 2
(-1700 3200);
DISPLAY 1.234043 (-1700 3200);
PAINT GREEN (-1700 3200);
DISPLAY INVISIBLE (-1700 3200);
FORCEPROP 1 LAST HDL_TAP TRUE
J 2
(-2025 3125);
DISPLAY 1.234043 (-2025 3125);
PAINT GREEN (-2025 3125);
DISPLAY INVISIBLE (-2025 3125);
FORCEPROP 1 LAST PATH I78
J 2
(-1700 3250);
DISPLAY 0.936170 (-1700 3250);
PAINT GREEN (-1700 3250);
DISPLAY INVISIBLE (-1700 3250);
FORCEADD TAP..6
R 2
(-1700 3150);
FORCEPROP 3 LASTPIN (-1750 3150) SIG_NAME M_K_DQ<28>
J 0
(-1740 3160);
DISPLAY 0.659574 (-1740 3160);
PAINT MONO (-1740 3160);
DISPLAY INVISIBLE (-1740 3160);
FORCEPROP 1 LASTPIN (-1750 3150) BN 28
J 2
(-1700 3160);
DISPLAY 0.617021 (-1700 3160);
PAINT PINK (-1700 3160);
FORCEPROP 2 LAST CDS_LIB mstr_standard
J 2
(-1700 3150);
DISPLAY 0.787234 (-1700 3150);
PAINT MONO (-1700 3150);
DISPLAY INVISIBLE (-1700 3150);
FORCEPROP 1 LAST BODY_TYPE PLUMBING
J 2
(-1700 3100);
DISPLAY 1.234043 (-1700 3100);
PAINT GREEN (-1700 3100);
DISPLAY INVISIBLE (-1700 3100);
FORCEPROP 1 LAST HDL_TAP TRUE
J 2
(-2025 3025);
DISPLAY 1.234043 (-2025 3025);
PAINT GREEN (-2025 3025);
DISPLAY INVISIBLE (-2025 3025);
FORCEPROP 1 LAST PATH I79
J 2
(-1700 3150);
DISPLAY 0.936170 (-1700 3150);
PAINT GREEN (-1700 3150);
DISPLAY INVISIBLE (-1700 3150);
FORCEADD TAP..6
R 2
(900 4750);
FORCEPROP 3 LASTPIN (850 4750) SIG_NAME M_K_DQS_DN<13>
J 0
(860 4760);
DISPLAY 0.659574 (860 4760);
PAINT MONO (860 4760);
DISPLAY INVISIBLE (860 4760);
FORCEPROP 1 LASTPIN (850 4750) BN 13
J 2
(900 4760);
DISPLAY 0.617021 (900 4760);
PAINT PINK (900 4760);
FORCEPROP 2 LAST CDS_LIB mstr_standard
J 0
(900 4750);
DISPLAY 0.787234 (900 4750);
PAINT MONO (900 4750);
DISPLAY INVISIBLE (900 4750);
FORCEPROP 1 LAST BODY_TYPE PLUMBING
J 2
(900 4700);
DISPLAY 1.234043 (900 4700);
PAINT GREEN (900 4700);
DISPLAY INVISIBLE (900 4700);
FORCEPROP 1 LAST HDL_TAP TRUE
J 2
(575 4625);
DISPLAY 1.234043 (575 4625);
PAINT GREEN (575 4625);
DISPLAY INVISIBLE (575 4625);
FORCEPROP 1 LAST PATH I8
J 2
(900 4750);
DISPLAY 0.936170 (900 4750);
PAINT GREEN (900 4750);
DISPLAY INVISIBLE (900 4750);
FORCEADD TAP..6
R 2
(-1700 3300);
FORCEPROP 3 LASTPIN (-1750 3300) SIG_NAME M_K_DQ<33>
J 0
(-1740 3310);
DISPLAY 0.659574 (-1740 3310);
PAINT MONO (-1740 3310);
DISPLAY INVISIBLE (-1740 3310);
FORCEPROP 1 LASTPIN (-1750 3300) BN 33
J 2
(-1700 3310);
DISPLAY 0.617021 (-1700 3310);
PAINT PINK (-1700 3310);
FORCEPROP 2 LAST CDS_LIB mstr_standard
J 2
(-1700 3300);
DISPLAY 0.787234 (-1700 3300);
PAINT MONO (-1700 3300);
DISPLAY INVISIBLE (-1700 3300);
FORCEPROP 1 LAST BODY_TYPE PLUMBING
J 2
(-1700 3250);
DISPLAY 1.234043 (-1700 3250);
PAINT GREEN (-1700 3250);
DISPLAY INVISIBLE (-1700 3250);
FORCEPROP 1 LAST HDL_TAP TRUE
J 2
(-2025 3175);
DISPLAY 1.234043 (-2025 3175);
PAINT GREEN (-2025 3175);
DISPLAY INVISIBLE (-2025 3175);
FORCEPROP 1 LAST PATH I80
J 2
(-1700 3300);
DISPLAY 0.936170 (-1700 3300);
PAINT GREEN (-1700 3300);
DISPLAY INVISIBLE (-1700 3300);
FORCEADD TAP..6
R 2
(-1700 3350);
FORCEPROP 3 LASTPIN (-1750 3350) SIG_NAME M_K_DQ<32>
J 0
(-1740 3360);
DISPLAY 0.659574 (-1740 3360);
PAINT MONO (-1740 3360);
DISPLAY INVISIBLE (-1740 3360);
FORCEPROP 1 LASTPIN (-1750 3350) BN 32
J 2
(-1700 3360);
DISPLAY 0.617021 (-1700 3360);
PAINT PINK (-1700 3360);
FORCEPROP 2 LAST CDS_LIB mstr_standard
J 2
(-1700 3350);
DISPLAY 0.787234 (-1700 3350);
PAINT MONO (-1700 3350);
DISPLAY INVISIBLE (-1700 3350);
FORCEPROP 1 LAST BODY_TYPE PLUMBING
J 2
(-1700 3300);
DISPLAY 1.234043 (-1700 3300);
PAINT GREEN (-1700 3300);
DISPLAY INVISIBLE (-1700 3300);
FORCEPROP 1 LAST HDL_TAP TRUE
J 2
(-2025 3225);
DISPLAY 1.234043 (-2025 3225);
PAINT GREEN (-2025 3225);
DISPLAY INVISIBLE (-2025 3225);
FORCEPROP 1 LAST PATH I81
J 2
(-1700 3350);
DISPLAY 0.936170 (-1700 3350);
PAINT GREEN (-1700 3350);
DISPLAY INVISIBLE (-1700 3350);
FORCEADD TAP..6
R 2
(-1700 2950);
FORCEPROP 3 LASTPIN (-1750 2950) SIG_NAME M_K_DQ<24>
J 0
(-1740 2960);
DISPLAY 0.659574 (-1740 2960);
PAINT MONO (-1740 2960);
DISPLAY INVISIBLE (-1740 2960);
FORCEPROP 1 LASTPIN (-1750 2950) BN 24
J 2
(-1700 2960);
DISPLAY 0.617021 (-1700 2960);
PAINT PINK (-1700 2960);
FORCEPROP 2 LAST CDS_LIB mstr_standard
J 2
(-1700 2950);
DISPLAY 0.787234 (-1700 2950);
PAINT MONO (-1700 2950);
DISPLAY INVISIBLE (-1700 2950);
FORCEPROP 1 LAST BODY_TYPE PLUMBING
J 2
(-1700 2900);
DISPLAY 1.234043 (-1700 2900);
PAINT GREEN (-1700 2900);
DISPLAY INVISIBLE (-1700 2900);
FORCEPROP 1 LAST HDL_TAP TRUE
J 2
(-2025 2825);
DISPLAY 1.234043 (-2025 2825);
PAINT GREEN (-2025 2825);
DISPLAY INVISIBLE (-2025 2825);
FORCEPROP 1 LAST PATH I82
J 2
(-1700 2950);
DISPLAY 0.936170 (-1700 2950);
PAINT GREEN (-1700 2950);
DISPLAY INVISIBLE (-1700 2950);
FORCEADD TAP..6
R 2
(-1700 2900);
FORCEPROP 3 LASTPIN (-1750 2900) SIG_NAME M_K_DQ<25>
J 0
(-1740 2910);
DISPLAY 0.659574 (-1740 2910);
PAINT MONO (-1740 2910);
DISPLAY INVISIBLE (-1740 2910);
FORCEPROP 1 LASTPIN (-1750 2900) BN 25
J 2
(-1700 2910);
DISPLAY 0.617021 (-1700 2910);
PAINT PINK (-1700 2910);
FORCEPROP 2 LAST CDS_LIB mstr_standard
J 2
(-1700 2900);
DISPLAY 0.787234 (-1700 2900);
PAINT MONO (-1700 2900);
DISPLAY INVISIBLE (-1700 2900);
FORCEPROP 1 LAST BODY_TYPE PLUMBING
J 2
(-1700 2850);
DISPLAY 1.234043 (-1700 2850);
PAINT GREEN (-1700 2850);
DISPLAY INVISIBLE (-1700 2850);
FORCEPROP 1 LAST HDL_TAP TRUE
J 2
(-2025 2775);
DISPLAY 1.234043 (-2025 2775);
PAINT GREEN (-2025 2775);
DISPLAY INVISIBLE (-2025 2775);
FORCEPROP 1 LAST PATH I83
J 2
(-1700 2900);
DISPLAY 0.936170 (-1700 2900);
PAINT GREEN (-1700 2900);
DISPLAY INVISIBLE (-1700 2900);
FORCEADD TAP..6
R 2
(-1700 3000);
FORCEPROP 3 LASTPIN (-1750 3000) SIG_NAME M_K_DQ<27>
J 0
(-1740 3010);
DISPLAY 0.659574 (-1740 3010);
PAINT MONO (-1740 3010);
DISPLAY INVISIBLE (-1740 3010);
FORCEPROP 1 LASTPIN (-1750 3000) BN 27
J 2
(-1700 3010);
DISPLAY 0.617021 (-1700 3010);
PAINT PINK (-1700 3010);
FORCEPROP 2 LAST CDS_LIB mstr_standard
J 2
(-1700 3000);
DISPLAY 0.787234 (-1700 3000);
PAINT MONO (-1700 3000);
DISPLAY INVISIBLE (-1700 3000);
FORCEPROP 1 LAST BODY_TYPE PLUMBING
J 2
(-1700 2950);
DISPLAY 1.234043 (-1700 2950);
PAINT GREEN (-1700 2950);
DISPLAY INVISIBLE (-1700 2950);
FORCEPROP 1 LAST HDL_TAP TRUE
J 2
(-2025 2875);
DISPLAY 1.234043 (-2025 2875);
PAINT GREEN (-2025 2875);
DISPLAY INVISIBLE (-2025 2875);
FORCEPROP 1 LAST PATH I84
J 2
(-1700 3000);
DISPLAY 0.936170 (-1700 3000);
PAINT GREEN (-1700 3000);
DISPLAY INVISIBLE (-1700 3000);
FORCEADD TAP..6
R 2
(-1700 3100);
FORCEPROP 3 LASTPIN (-1750 3100) SIG_NAME M_K_DQ<29>
J 0
(-1740 3110);
DISPLAY 0.659574 (-1740 3110);
PAINT MONO (-1740 3110);
DISPLAY INVISIBLE (-1740 3110);
FORCEPROP 1 LASTPIN (-1750 3100) BN 29
J 2
(-1700 3110);
DISPLAY 0.617021 (-1700 3110);
PAINT PINK (-1700 3110);
FORCEPROP 2 LAST CDS_LIB mstr_standard
J 2
(-1700 3100);
DISPLAY 0.787234 (-1700 3100);
PAINT MONO (-1700 3100);
DISPLAY INVISIBLE (-1700 3100);
FORCEPROP 1 LAST BODY_TYPE PLUMBING
J 2
(-1700 3050);
DISPLAY 1.234043 (-1700 3050);
PAINT GREEN (-1700 3050);
DISPLAY INVISIBLE (-1700 3050);
FORCEPROP 1 LAST HDL_TAP TRUE
J 2
(-2025 2975);
DISPLAY 1.234043 (-2025 2975);
PAINT GREEN (-2025 2975);
DISPLAY INVISIBLE (-2025 2975);
FORCEPROP 1 LAST PATH I85
J 2
(-1700 3100);
DISPLAY 0.936170 (-1700 3100);
PAINT GREEN (-1700 3100);
DISPLAY INVISIBLE (-1700 3100);
FORCEADD TAP..6
R 2
(-1700 3050);
FORCEPROP 3 LASTPIN (-1750 3050) SIG_NAME M_K_DQ<26>
J 0
(-1740 3060);
DISPLAY 0.659574 (-1740 3060);
PAINT MONO (-1740 3060);
DISPLAY INVISIBLE (-1740 3060);
FORCEPROP 1 LASTPIN (-1750 3050) BN 26
J 2
(-1700 3060);
DISPLAY 0.617021 (-1700 3060);
PAINT PINK (-1700 3060);
FORCEPROP 2 LAST CDS_LIB mstr_standard
J 2
(-1700 3050);
DISPLAY 0.787234 (-1700 3050);
PAINT MONO (-1700 3050);
DISPLAY INVISIBLE (-1700 3050);
FORCEPROP 1 LAST BODY_TYPE PLUMBING
J 2
(-1700 3000);
DISPLAY 1.234043 (-1700 3000);
PAINT GREEN (-1700 3000);
DISPLAY INVISIBLE (-1700 3000);
FORCEPROP 1 LAST HDL_TAP TRUE
J 2
(-2025 2925);
DISPLAY 1.234043 (-2025 2925);
PAINT GREEN (-2025 2925);
DISPLAY INVISIBLE (-2025 2925);
FORCEPROP 1 LAST PATH I86
J 2
(-1700 3050);
DISPLAY 0.936170 (-1700 3050);
PAINT GREEN (-1700 3050);
DISPLAY INVISIBLE (-1700 3050);
FORCEADD TAP..6
R 2
(-1700 2650);
FORCEPROP 3 LASTPIN (-1750 2650) SIG_NAME M_K_DQ<18>
J 0
(-1740 2660);
DISPLAY 0.659574 (-1740 2660);
PAINT MONO (-1740 2660);
DISPLAY INVISIBLE (-1740 2660);
FORCEPROP 1 LASTPIN (-1750 2650) BN 18
J 2
(-1700 2660);
DISPLAY 0.617021 (-1700 2660);
PAINT PINK (-1700 2660);
FORCEPROP 2 LAST CDS_LIB mstr_standard
J 2
(-1700 2650);
DISPLAY 0.787234 (-1700 2650);
PAINT MONO (-1700 2650);
DISPLAY INVISIBLE (-1700 2650);
FORCEPROP 1 LAST BODY_TYPE PLUMBING
J 2
(-1700 2600);
DISPLAY 1.234043 (-1700 2600);
PAINT GREEN (-1700 2600);
DISPLAY INVISIBLE (-1700 2600);
FORCEPROP 1 LAST HDL_TAP TRUE
J 2
(-2025 2525);
DISPLAY 1.234043 (-2025 2525);
PAINT GREEN (-2025 2525);
DISPLAY INVISIBLE (-2025 2525);
FORCEPROP 1 LAST PATH I87
J 2
(-1700 2650);
DISPLAY 0.936170 (-1700 2650);
PAINT GREEN (-1700 2650);
DISPLAY INVISIBLE (-1700 2650);
FORCEADD TAP..6
R 2
(-1700 2700);
FORCEPROP 3 LASTPIN (-1750 2700) SIG_NAME M_K_DQ<21>
J 0
(-1740 2710);
DISPLAY 0.659574 (-1740 2710);
PAINT MONO (-1740 2710);
DISPLAY INVISIBLE (-1740 2710);
FORCEPROP 1 LASTPIN (-1750 2700) BN 21
J 2
(-1700 2710);
DISPLAY 0.617021 (-1700 2710);
PAINT PINK (-1700 2710);
FORCEPROP 2 LAST CDS_LIB mstr_standard
J 2
(-1700 2700);
DISPLAY 0.787234 (-1700 2700);
PAINT MONO (-1700 2700);
DISPLAY INVISIBLE (-1700 2700);
FORCEPROP 1 LAST BODY_TYPE PLUMBING
J 2
(-1700 2650);
DISPLAY 1.234043 (-1700 2650);
PAINT GREEN (-1700 2650);
DISPLAY INVISIBLE (-1700 2650);
FORCEPROP 1 LAST HDL_TAP TRUE
J 2
(-2025 2575);
DISPLAY 1.234043 (-2025 2575);
PAINT GREEN (-2025 2575);
DISPLAY INVISIBLE (-2025 2575);
FORCEPROP 1 LAST PATH I88
J 2
(-1700 2700);
DISPLAY 0.936170 (-1700 2700);
PAINT GREEN (-1700 2700);
DISPLAY INVISIBLE (-1700 2700);
FORCEADD TAP..6
R 2
(-1700 2750);
FORCEPROP 3 LASTPIN (-1750 2750) SIG_NAME M_K_DQ<20>
J 0
(-1740 2760);
DISPLAY 0.659574 (-1740 2760);
PAINT MONO (-1740 2760);
DISPLAY INVISIBLE (-1740 2760);
FORCEPROP 1 LASTPIN (-1750 2750) BN 20
J 2
(-1700 2760);
DISPLAY 0.617021 (-1700 2760);
PAINT PINK (-1700 2760);
FORCEPROP 2 LAST CDS_LIB mstr_standard
J 2
(-1700 2750);
DISPLAY 0.787234 (-1700 2750);
PAINT MONO (-1700 2750);
DISPLAY INVISIBLE (-1700 2750);
FORCEPROP 1 LAST BODY_TYPE PLUMBING
J 2
(-1700 2700);
DISPLAY 1.234043 (-1700 2700);
PAINT GREEN (-1700 2700);
DISPLAY INVISIBLE (-1700 2700);
FORCEPROP 1 LAST HDL_TAP TRUE
J 2
(-2025 2625);
DISPLAY 1.234043 (-2025 2625);
PAINT GREEN (-2025 2625);
DISPLAY INVISIBLE (-2025 2625);
FORCEPROP 1 LAST PATH I89
J 2
(-1700 2750);
DISPLAY 0.936170 (-1700 2750);
PAINT GREEN (-1700 2750);
DISPLAY INVISIBLE (-1700 2750);
FORCEADD TAP..6
R 2
(900 4650);
FORCEPROP 3 LASTPIN (850 4650) SIG_NAME M_K_DQS_DN<12>
J 0
(860 4660);
DISPLAY 0.659574 (860 4660);
PAINT MONO (860 4660);
DISPLAY INVISIBLE (860 4660);
FORCEPROP 1 LASTPIN (850 4650) BN 12
J 2
(900 4660);
DISPLAY 0.617021 (900 4660);
PAINT PINK (900 4660);
FORCEPROP 2 LAST CDS_LIB mstr_standard
J 0
(900 4650);
DISPLAY 0.787234 (900 4650);
PAINT MONO (900 4650);
DISPLAY INVISIBLE (900 4650);
FORCEPROP 1 LAST BODY_TYPE PLUMBING
J 2
(900 4600);
DISPLAY 1.234043 (900 4600);
PAINT GREEN (900 4600);
DISPLAY INVISIBLE (900 4600);
FORCEPROP 1 LAST HDL_TAP TRUE
J 2
(575 4525);
DISPLAY 1.234043 (575 4525);
PAINT GREEN (575 4525);
DISPLAY INVISIBLE (575 4525);
FORCEPROP 1 LAST PATH I9
J 2
(900 4650);
DISPLAY 0.936170 (900 4650);
PAINT GREEN (900 4650);
DISPLAY INVISIBLE (900 4650);
FORCEADD TAP..6
R 2
(-1700 2850);
FORCEPROP 3 LASTPIN (-1750 2850) SIG_NAME M_K_DQ<22>
J 0
(-1740 2860);
DISPLAY 0.659574 (-1740 2860);
PAINT MONO (-1740 2860);
DISPLAY INVISIBLE (-1740 2860);
FORCEPROP 1 LASTPIN (-1750 2850) BN 22
J 2
(-1700 2860);
DISPLAY 0.617021 (-1700 2860);
PAINT PINK (-1700 2860);
FORCEPROP 2 LAST CDS_LIB mstr_standard
J 2
(-1700 2850);
DISPLAY 0.787234 (-1700 2850);
PAINT MONO (-1700 2850);
DISPLAY INVISIBLE (-1700 2850);
FORCEPROP 1 LAST BODY_TYPE PLUMBING
J 2
(-1700 2800);
DISPLAY 1.234043 (-1700 2800);
PAINT GREEN (-1700 2800);
DISPLAY INVISIBLE (-1700 2800);
FORCEPROP 1 LAST HDL_TAP TRUE
J 2
(-2025 2725);
DISPLAY 1.234043 (-2025 2725);
PAINT GREEN (-2025 2725);
DISPLAY INVISIBLE (-2025 2725);
FORCEPROP 1 LAST PATH I90
J 2
(-1700 2850);
DISPLAY 0.936170 (-1700 2850);
PAINT GREEN (-1700 2850);
DISPLAY INVISIBLE (-1700 2850);
FORCEADD TAP..6
R 2
(-1700 2800);
FORCEPROP 3 LASTPIN (-1750 2800) SIG_NAME M_K_DQ<23>
J 0
(-1740 2810);
DISPLAY 0.659574 (-1740 2810);
PAINT MONO (-1740 2810);
DISPLAY INVISIBLE (-1740 2810);
FORCEPROP 1 LASTPIN (-1750 2800) BN 23
J 2
(-1700 2810);
DISPLAY 0.617021 (-1700 2810);
PAINT PINK (-1700 2810);
FORCEPROP 2 LAST CDS_LIB mstr_standard
J 2
(-1700 2800);
DISPLAY 0.787234 (-1700 2800);
PAINT MONO (-1700 2800);
DISPLAY INVISIBLE (-1700 2800);
FORCEPROP 1 LAST BODY_TYPE PLUMBING
J 2
(-1700 2750);
DISPLAY 1.234043 (-1700 2750);
PAINT GREEN (-1700 2750);
DISPLAY INVISIBLE (-1700 2750);
FORCEPROP 1 LAST HDL_TAP TRUE
J 2
(-2025 2675);
DISPLAY 1.234043 (-2025 2675);
PAINT GREEN (-2025 2675);
DISPLAY INVISIBLE (-2025 2675);
FORCEPROP 1 LAST PATH I91
J 2
(-1700 2800);
DISPLAY 0.936170 (-1700 2800);
PAINT GREEN (-1700 2800);
DISPLAY INVISIBLE (-1700 2800);
FORCEADD TAP..6
R 2
(-1700 2400);
FORCEPROP 3 LASTPIN (-1750 2400) SIG_NAME M_K_DQ<15>
J 0
(-1740 2410);
DISPLAY 0.659574 (-1740 2410);
PAINT MONO (-1740 2410);
DISPLAY INVISIBLE (-1740 2410);
FORCEPROP 1 LASTPIN (-1750 2400) BN 15
J 2
(-1700 2410);
DISPLAY 0.617021 (-1700 2410);
PAINT PINK (-1700 2410);
FORCEPROP 2 LAST CDS_LIB mstr_standard
J 2
(-1700 2400);
DISPLAY 0.787234 (-1700 2400);
PAINT MONO (-1700 2400);
DISPLAY INVISIBLE (-1700 2400);
FORCEPROP 1 LAST BODY_TYPE PLUMBING
J 2
(-1700 2350);
DISPLAY 1.234043 (-1700 2350);
PAINT GREEN (-1700 2350);
DISPLAY INVISIBLE (-1700 2350);
FORCEPROP 1 LAST HDL_TAP TRUE
J 2
(-2025 2275);
DISPLAY 1.234043 (-2025 2275);
PAINT GREEN (-2025 2275);
DISPLAY INVISIBLE (-2025 2275);
FORCEPROP 1 LAST PATH I92
J 2
(-1700 2400);
DISPLAY 0.936170 (-1700 2400);
PAINT GREEN (-1700 2400);
DISPLAY INVISIBLE (-1700 2400);
FORCEADD TAP..6
R 2
(-1700 2450);
FORCEPROP 3 LASTPIN (-1750 2450) SIG_NAME M_K_DQ<14>
J 0
(-1740 2460);
DISPLAY 0.659574 (-1740 2460);
PAINT MONO (-1740 2460);
DISPLAY INVISIBLE (-1740 2460);
FORCEPROP 1 LASTPIN (-1750 2450) BN 14
J 2
(-1700 2460);
DISPLAY 0.617021 (-1700 2460);
PAINT PINK (-1700 2460);
FORCEPROP 2 LAST CDS_LIB mstr_standard
J 2
(-1700 2450);
DISPLAY 0.787234 (-1700 2450);
PAINT MONO (-1700 2450);
DISPLAY INVISIBLE (-1700 2450);
FORCEPROP 1 LAST BODY_TYPE PLUMBING
J 2
(-1700 2400);
DISPLAY 1.234043 (-1700 2400);
PAINT GREEN (-1700 2400);
DISPLAY INVISIBLE (-1700 2400);
FORCEPROP 1 LAST HDL_TAP TRUE
J 2
(-2025 2325);
DISPLAY 1.234043 (-2025 2325);
PAINT GREEN (-2025 2325);
DISPLAY INVISIBLE (-2025 2325);
FORCEPROP 1 LAST PATH I93
J 2
(-1700 2450);
DISPLAY 0.936170 (-1700 2450);
PAINT GREEN (-1700 2450);
DISPLAY INVISIBLE (-1700 2450);
FORCEADD TAP..6
R 2
(-1700 2550);
FORCEPROP 3 LASTPIN (-1750 2550) SIG_NAME M_K_DQ<16>
J 0
(-1740 2560);
DISPLAY 0.659574 (-1740 2560);
PAINT MONO (-1740 2560);
DISPLAY INVISIBLE (-1740 2560);
FORCEPROP 1 LASTPIN (-1750 2550) BN 16
J 2
(-1700 2560);
DISPLAY 0.617021 (-1700 2560);
PAINT PINK (-1700 2560);
FORCEPROP 2 LAST CDS_LIB mstr_standard
J 2
(-1700 2550);
DISPLAY 0.787234 (-1700 2550);
PAINT MONO (-1700 2550);
DISPLAY INVISIBLE (-1700 2550);
FORCEPROP 1 LAST BODY_TYPE PLUMBING
J 2
(-1700 2500);
DISPLAY 1.234043 (-1700 2500);
PAINT GREEN (-1700 2500);
DISPLAY INVISIBLE (-1700 2500);
FORCEPROP 1 LAST HDL_TAP TRUE
J 2
(-2025 2425);
DISPLAY 1.234043 (-2025 2425);
PAINT GREEN (-2025 2425);
DISPLAY INVISIBLE (-2025 2425);
FORCEPROP 1 LAST PATH I94
J 2
(-1700 2550);
DISPLAY 0.936170 (-1700 2550);
PAINT GREEN (-1700 2550);
DISPLAY INVISIBLE (-1700 2550);
FORCEADD TAP..6
R 2
(-1700 2500);
FORCEPROP 3 LASTPIN (-1750 2500) SIG_NAME M_K_DQ<17>
J 0
(-1740 2510);
DISPLAY 0.659574 (-1740 2510);
PAINT MONO (-1740 2510);
DISPLAY INVISIBLE (-1740 2510);
FORCEPROP 1 LASTPIN (-1750 2500) BN 17
J 2
(-1700 2510);
DISPLAY 0.617021 (-1700 2510);
PAINT PINK (-1700 2510);
FORCEPROP 2 LAST CDS_LIB mstr_standard
J 2
(-1700 2500);
DISPLAY 0.787234 (-1700 2500);
PAINT MONO (-1700 2500);
DISPLAY INVISIBLE (-1700 2500);
FORCEPROP 1 LAST BODY_TYPE PLUMBING
J 2
(-1700 2450);
DISPLAY 1.234043 (-1700 2450);
PAINT GREEN (-1700 2450);
DISPLAY INVISIBLE (-1700 2450);
FORCEPROP 1 LAST HDL_TAP TRUE
J 2
(-2025 2375);
DISPLAY 1.234043 (-2025 2375);
PAINT GREEN (-2025 2375);
DISPLAY INVISIBLE (-2025 2375);
FORCEPROP 1 LAST PATH I95
J 2
(-1700 2500);
DISPLAY 0.936170 (-1700 2500);
PAINT GREEN (-1700 2500);
DISPLAY INVISIBLE (-1700 2500);
FORCEADD TAP..6
R 2
(-1700 2600);
FORCEPROP 3 LASTPIN (-1750 2600) SIG_NAME M_K_DQ<19>
J 0
(-1740 2610);
DISPLAY 0.659574 (-1740 2610);
PAINT MONO (-1740 2610);
DISPLAY INVISIBLE (-1740 2610);
FORCEPROP 1 LASTPIN (-1750 2600) BN 19
J 2
(-1700 2610);
DISPLAY 0.617021 (-1700 2610);
PAINT PINK (-1700 2610);
FORCEPROP 2 LAST CDS_LIB mstr_standard
J 2
(-1700 2600);
DISPLAY 0.787234 (-1700 2600);
PAINT MONO (-1700 2600);
DISPLAY INVISIBLE (-1700 2600);
FORCEPROP 1 LAST BODY_TYPE PLUMBING
J 2
(-1700 2550);
DISPLAY 1.234043 (-1700 2550);
PAINT GREEN (-1700 2550);
DISPLAY INVISIBLE (-1700 2550);
FORCEPROP 1 LAST HDL_TAP TRUE
J 2
(-2025 2475);
DISPLAY 1.234043 (-2025 2475);
PAINT GREEN (-2025 2475);
DISPLAY INVISIBLE (-2025 2475);
FORCEPROP 1 LAST PATH I96
J 2
(-1700 2600);
DISPLAY 0.936170 (-1700 2600);
PAINT GREEN (-1700 2600);
DISPLAY INVISIBLE (-1700 2600);
FORCEADD TAP..6
R 2
(-1700 2350);
FORCEPROP 3 LASTPIN (-1750 2350) SIG_NAME M_K_DQ<12>
J 0
(-1740 2360);
DISPLAY 0.659574 (-1740 2360);
PAINT MONO (-1740 2360);
DISPLAY INVISIBLE (-1740 2360);
FORCEPROP 1 LASTPIN (-1750 2350) BN 12
J 2
(-1700 2360);
DISPLAY 0.617021 (-1700 2360);
PAINT PINK (-1700 2360);
FORCEPROP 2 LAST CDS_LIB mstr_standard
J 2
(-1700 2350);
DISPLAY 0.787234 (-1700 2350);
PAINT MONO (-1700 2350);
DISPLAY INVISIBLE (-1700 2350);
FORCEPROP 1 LAST BODY_TYPE PLUMBING
J 2
(-1700 2300);
DISPLAY 1.234043 (-1700 2300);
PAINT GREEN (-1700 2300);
DISPLAY INVISIBLE (-1700 2300);
FORCEPROP 1 LAST HDL_TAP TRUE
J 2
(-2025 2225);
DISPLAY 1.234043 (-2025 2225);
PAINT GREEN (-2025 2225);
DISPLAY INVISIBLE (-2025 2225);
FORCEPROP 1 LAST PATH I97
J 2
(-1700 2350);
DISPLAY 0.936170 (-1700 2350);
PAINT GREEN (-1700 2350);
DISPLAY INVISIBLE (-1700 2350);
FORCEADD TAP..6
R 2
(-1700 2250);
FORCEPROP 3 LASTPIN (-1750 2250) SIG_NAME M_K_DQ<10>
J 0
(-1740 2260);
DISPLAY 0.659574 (-1740 2260);
PAINT MONO (-1740 2260);
DISPLAY INVISIBLE (-1740 2260);
FORCEPROP 1 LASTPIN (-1750 2250) BN 10
J 2
(-1700 2260);
DISPLAY 0.617021 (-1700 2260);
PAINT PINK (-1700 2260);
FORCEPROP 2 LAST CDS_LIB mstr_standard
J 2
(-1700 2250);
DISPLAY 0.787234 (-1700 2250);
PAINT MONO (-1700 2250);
DISPLAY INVISIBLE (-1700 2250);
FORCEPROP 1 LAST BODY_TYPE PLUMBING
J 2
(-1700 2200);
DISPLAY 1.234043 (-1700 2200);
PAINT GREEN (-1700 2200);
DISPLAY INVISIBLE (-1700 2200);
FORCEPROP 1 LAST HDL_TAP TRUE
J 2
(-2025 2125);
DISPLAY 1.234043 (-2025 2125);
PAINT GREEN (-2025 2125);
DISPLAY INVISIBLE (-2025 2125);
FORCEPROP 1 LAST PATH I98
J 2
(-1700 2250);
DISPLAY 0.936170 (-1700 2250);
PAINT GREEN (-1700 2250);
DISPLAY INVISIBLE (-1700 2250);
FORCEADD TAP..6
R 2
(-1700 2300);
FORCEPROP 3 LASTPIN (-1750 2300) SIG_NAME M_K_DQ<13>
J 0
(-1740 2310);
DISPLAY 0.659574 (-1740 2310);
PAINT MONO (-1740 2310);
DISPLAY INVISIBLE (-1740 2310);
FORCEPROP 1 LASTPIN (-1750 2300) BN 13
J 2
(-1700 2310);
DISPLAY 0.617021 (-1700 2310);
PAINT PINK (-1700 2310);
FORCEPROP 2 LAST CDS_LIB mstr_standard
J 2
(-1700 2300);
DISPLAY 0.787234 (-1700 2300);
PAINT MONO (-1700 2300);
DISPLAY INVISIBLE (-1700 2300);
FORCEPROP 1 LAST BODY_TYPE PLUMBING
J 2
(-1700 2250);
DISPLAY 1.234043 (-1700 2250);
PAINT GREEN (-1700 2250);
DISPLAY INVISIBLE (-1700 2250);
FORCEPROP 1 LAST HDL_TAP TRUE
J 2
(-2025 2175);
DISPLAY 1.234043 (-2025 2175);
PAINT GREEN (-2025 2175);
DISPLAY INVISIBLE (-2025 2175);
FORCEPROP 1 LAST PATH I99
J 2
(-1700 2300);
DISPLAY 0.936170 (-1700 2300);
PAINT GREEN (-1700 2300);
DISPLAY INVISIBLE (-1700 2300);
FORCEADD INTEL_CORP_BPAGE..1
(2650 500);
FORCEPROP 1 LAST CDS_CON_LAST_MODIFIED Fri Jun 16 17:48:31 2017
J 0
(1225 825);
DISPLAY 0.787234 (1225 825);
PAINT ORANGE (1225 825);
DISPLAY INVISIBLE (1225 825);
FORCEPROP 1 LAST CUSTOM_TXT_CDS <CURRENT_DESIGN_SHEET> OF <TOTAL_DESIGN_SHEETS>
J 0
(2150 525);
PAINT ORANGE (2150 525);
FORCEPROP 1 LAST CUSTOM_TXT_CDS <CON_LAST_MODIFIED>
J 0
(-1350 600);
PAINT ORANGE (-1350 600);
FORCEPROP 2 LAST CUSTOM_TXT_CDS <XR_PAGE_TITLE>
J 0
(-5240 5750);
DISPLAY 0.638298 (-5240 5750);
PAINT PINK (-5240 5750);
DISPLAY INVISIBLE (-5240 5750);
FORCEPROP 1 LAST SCH_TITLE CPU1 DDR4 CH K DIMM0
J 0
(-5300 550);
DISPLAY 1.212766 (-5300 550);
PAINT WHITE (-5300 550);
FORCEPROP 2 LAST CDS_LIB mstr_symbols
J 0
(2650 500);
DISPLAY 0.787234 (2650 500);
PAINT MONO (2650 500);
DISPLAY INVISIBLE (2650 500);
FORCEPROP 2 LAST PAGE_BORDER TRUE
J 0
(-5240 5750);
DISPLAY 0.680851 (-5240 5750);
PAINT PINK (-5240 5750);
DISPLAY INVISIBLE (-5240 5750);
FORCEPROP 1 LAST COMMENT_BODY TRUE
J 0
(2660 510);
DISPLAY 0.382979 (2660 510);
PAINT GREEN (2660 510);
DISPLAY INVISIBLE (2660 510);
FORCEPROP 2 LAST CDS_XR_PAGE_TITLE CR-83 : @BASEBOARD_FAB2_LIB.BASEBOARD_FAB2(SCH_1):PAGE83
J 0
(-5240 5750);
DISPLAY 0.638298 (-5240 5750);
PAINT PINK (-5240 5750);
DISPLAY INVISIBLE (-5240 5750);
FORCEADD BOM_NOTE..1
(-5000 5275);
FORCEPROP 0 LAST L1 STUFF FOR SKU A & B
J 0
(-5150 5175);
DISPLAY 1.063830 (-5150 5175);
PAINT WHITE (-5150 5175);
FORCEPROP 2 LAST CDS_LIB mstr_symbols
J 0
(-5000 5275);
PAINT ORANGE (-5000 5275);
DISPLAY INVISIBLE (-5000 5275);
FORCEPROP 2 LAST BOM_COST SB
J 0
(-5150 5250);
DISPLAY 1.361702 (-5150 5250);
PAINT ORANGE (-5150 5250);
DISPLAY INVISIBLE (-5150 5250);
FORCEPROP 1 LAST COMMENT_BODY TRUE
J 0
(-4975 5375);
DISPLAY 1.319149 (-4975 5375);
PAINT ORANGE (-4975 5375);
DISPLAY INVISIBLE (-4975 5375);
FORCEPROP 2 LAST ROOM SB_HEADERS
J 0
(-5150 5250);
DISPLAY 1.361702 (-5150 5250);
PAINT ORANGE (-5150 5250);
DISPLAY INVISIBLE (-5150 5250);
WIRE 16 -1 (-1300 2575)(-1300 2500);
WIRE 16 -1 (-1300 2500)(-850 2500);
WIRE 16 -1 (-850 2450)(-850 2500);
WIRE 16 -1 (-850 2500)(-650 2500);
WIRE 16 -1 (-850 2400)(-850 2450);
WIRE 16 -1 (-850 2450)(-650 2450);
WIRE 16 -1 (-850 2350)(-850 2400);
WIRE 16 -1 (-850 2400)(-650 2400);
WIRE 16 -1 (-850 2300)(-850 2350);
WIRE 16 -1 (-850 2350)(-650 2350);
WIRE 16 -1 (-850 2250)(-850 2300);
WIRE 16 -1 (-850 2300)(-650 2300);
WIRE 16 -1 (-850 2200)(-850 2250);
WIRE 16 -1 (-850 2250)(-650 2250);
WIRE 16 -1 (-850 2150)(-850 2200);
WIRE 16 -1 (-850 2200)(-650 2200);
WIRE 16 -1 (-850 2100)(-850 2150);
WIRE 16 -1 (-850 2150)(-650 2150);
WIRE 16 -1 (-850 2050)(-850 2100);
WIRE 16 -1 (-850 2100)(-650 2100);
WIRE 16 -1 (-850 2000)(-850 2050);
WIRE 16 -1 (-850 2050)(-650 2050);
WIRE 16 -1 (-850 1950)(-850 2000);
WIRE 16 -1 (-850 2000)(-650 2000);
WIRE 16 -1 (-850 1900)(-850 1950);
WIRE 16 -1 (-850 1950)(-650 1950);
WIRE 16 -1 (-850 1850)(-850 1900);
WIRE 16 -1 (-850 1900)(-650 1900);
WIRE 16 -1 (-850 1800)(-850 1850);
WIRE 16 -1 (-850 1850)(-650 1850);
WIRE 16 -1 (-850 1750)(-850 1800);
WIRE 16 -1 (-850 1800)(-650 1800);
WIRE 16 -1 (-850 1700)(-850 1750);
WIRE 16 -1 (-850 1750)(-650 1750);
WIRE 16 -1 (-850 1650)(-850 1700);
WIRE 16 -1 (-850 1700)(-650 1700);
WIRE 16 -1 (-850 1600)(-850 1650);
WIRE 16 -1 (-850 1650)(-650 1650);
WIRE 16 -1 (-850 1550)(-850 1600);
WIRE 16 -1 (-850 1600)(-650 1600);
WIRE 16 -1 (-850 1500)(-850 1550);
WIRE 16 -1 (-850 1550)(-650 1550);
WIRE 16 -1 (-850 1450)(-850 1500);
WIRE 16 -1 (-850 1500)(-650 1500);
WIRE 16 -1 (-850 1400)(-850 1450);
WIRE 16 -1 (-850 1450)(-650 1450);
WIRE 16 -1 (-850 1350)(-850 1400);
WIRE 16 -1 (-850 1400)(-650 1400);
WIRE 16 -1 (-850 1300)(-850 1350);
WIRE 16 -1 (-850 1350)(-650 1350);
WIRE 16 -1 (-850 1250)(-850 1300);
WIRE 16 -1 (-850 1300)(-650 1300);
WIRE 16 -1 (-850 1250)(-650 1250);
WIRE 16 -1 (2500 1150)(2500 1250);
WIRE 16 -1 (2500 1250)(2500 1300);
WIRE 16 -1 (2500 1250)(2300 1250);
WIRE 16 -1 (2500 1300)(2500 1350);
WIRE 16 -1 (2500 1300)(2300 1300);
WIRE 16 -1 (2500 1350)(2500 1400);
WIRE 16 -1 (2500 1350)(2300 1350);
WIRE 16 -1 (2500 1400)(2500 1450);
WIRE 16 -1 (2500 1400)(2300 1400);
WIRE 16 -1 (2500 1450)(2500 1500);
WIRE 16 -1 (2500 1450)(2300 1450);
WIRE 16 -1 (2500 1500)(2500 1550);
WIRE 16 -1 (2500 1500)(2300 1500);
WIRE 16 -1 (2500 1550)(2500 1600);
WIRE 16 -1 (2500 1550)(2300 1550);
WIRE 16 -1 (2500 1600)(2500 1650);
WIRE 16 -1 (2500 1600)(2300 1600);
WIRE 16 -1 (2500 1650)(2500 1700);
WIRE 16 -1 (2500 1650)(2300 1650);
WIRE 16 -1 (2500 1700)(2500 1750);
WIRE 16 -1 (2500 1700)(2300 1700);
WIRE 16 -1 (2500 1750)(2500 1800);
WIRE 16 -1 (2500 1750)(2300 1750);
WIRE 16 -1 (2500 1800)(2500 1850);
WIRE 16 -1 (2500 1800)(2300 1800);
WIRE 16 -1 (2500 1850)(2500 1900);
WIRE 16 -1 (2500 1850)(2300 1850);
WIRE 16 -1 (2500 1900)(2500 1950);
WIRE 16 -1 (2500 1900)(2300 1900);
WIRE 16 -1 (2500 1950)(2500 2000);
WIRE 16 -1 (2500 1950)(2300 1950);
WIRE 16 -1 (2500 2000)(2500 2050);
WIRE 16 -1 (2500 2000)(2300 2000);
WIRE 16 -1 (2500 2050)(2500 2100);
WIRE 16 -1 (2500 2050)(2300 2050);
WIRE 16 -1 (2500 2100)(2500 2150);
WIRE 16 -1 (2500 2100)(2300 2100);
WIRE 16 -1 (2500 2150)(2500 2200);
WIRE 16 -1 (2500 2150)(2300 2150);
WIRE 16 -1 (2500 2200)(2500 2250);
WIRE 16 -1 (2500 2200)(2300 2200);
WIRE 16 -1 (2500 2250)(2500 2300);
WIRE 16 -1 (2500 2250)(2300 2250);
WIRE 16 -1 (2500 2300)(2500 2350);
WIRE 16 -1 (2500 2300)(2300 2300);
WIRE 16 -1 (2500 2350)(2500 2400);
WIRE 16 -1 (2500 2350)(2300 2350);
WIRE 16 -1 (2500 2400)(2500 2450);
WIRE 16 -1 (2500 2400)(2300 2400);
WIRE 16 -1 (2500 2450)(2500 2500);
WIRE 16 -1 (2500 2450)(2300 2450);
WIRE 16 -1 (2500 2500)(2500 2550);
WIRE 16 -1 (2500 2500)(2300 2500);
WIRE 16 -1 (2500 2550)(2500 2600);
WIRE 16 -1 (2500 2550)(2300 2550);
WIRE 16 -1 (2500 2600)(2500 2650);
WIRE 16 -1 (2500 2600)(2300 2600);
WIRE 16 -1 (2500 2650)(2500 2700);
WIRE 16 -1 (2500 2650)(2300 2650);
WIRE 16 -1 (2500 2700)(2500 2750);
WIRE 16 -1 (2500 2700)(2300 2700);
WIRE 16 -1 (2500 2750)(2500 2800);
WIRE 16 -1 (2500 2750)(2300 2750);
WIRE 16 -1 (2500 2800)(2500 2850);
WIRE 16 -1 (2500 2800)(2300 2800);
WIRE 16 -1 (2500 2850)(2500 2900);
WIRE 16 -1 (2500 2850)(2300 2850);
WIRE 16 -1 (2500 2900)(2500 2950);
WIRE 16 -1 (2500 2900)(2300 2900);
WIRE 16 -1 (2500 2950)(2500 3000);
WIRE 16 -1 (2500 2950)(2300 2950);
WIRE 16 -1 (2500 3000)(2500 3050);
WIRE 16 -1 (2500 3000)(2300 3000);
WIRE 16 -1 (2500 3050)(2500 3100);
WIRE 16 -1 (2500 3050)(2300 3050);
WIRE 16 -1 (2500 3100)(2500 3150);
WIRE 16 -1 (2500 3100)(2300 3100);
WIRE 16 -1 (2500 3150)(2500 3200);
WIRE 16 -1 (2500 3150)(2300 3150);
WIRE 16 -1 (2500 3200)(2500 3250);
WIRE 16 -1 (2500 3200)(2300 3200);
WIRE 16 -1 (2500 3250)(2500 3300);
WIRE 16 -1 (2500 3250)(2300 3250);
WIRE 16 -1 (2500 3300)(2500 3350);
WIRE 16 -1 (2500 3300)(2300 3300);
WIRE 16 -1 (2500 3350)(2500 3400);
WIRE 16 -1 (2500 3350)(2300 3350);
WIRE 16 -1 (2500 3400)(2500 3450);
WIRE 16 -1 (2500 3400)(2300 3400);
WIRE 16 -1 (2500 3450)(2500 3500);
WIRE 16 -1 (2500 3450)(2300 3450);
WIRE 16 -1 (2500 3500)(2500 3550);
WIRE 16 -1 (2500 3500)(2300 3500);
WIRE 16 -1 (2500 3550)(2300 3550);
WIRE 16 -1 (-1050 2750)(-1050 2650);
WIRE 16 -1 (-1050 2650)(-850 2650);
WIRE 16 -1 (-850 2600)(-850 2650);
WIRE 16 -1 (-850 2650)(-650 2650);
WIRE 16 -1 (-850 2600)(-650 2600);
WIRE 16 -1 (-5100 2000)(-5100 1900);
WIRE 16 -1 (-3150 2000)(-5100 2000);
WIRE 16 -1 (-3150 1950)(-3150 2000);
WIRE 16 -1 (-2950 2000)(-3150 2000);
WIRE 16 -1 (-3150 1900)(-3150 1950);
WIRE 16 -1 (-3150 1950)(-2950 1950);
WIRE 16 -1 (-2950 1900)(-3150 1900);
WIRE 16 -1 (-4600 1400)(-4600 1300);
WIRE 16 -1 (-850 3050)(-850 2950);
WIRE 16 -1 (-850 2950)(-850 2900);
WIRE 16 -1 (-850 2950)(-650 2950);
WIRE 16 -1 (-850 2850)(-850 2900);
WIRE 16 -1 (-850 2900)(-650 2900);
WIRE 16 -1 (-850 2850)(-850 2800);
WIRE 16 -1 (-850 2850)(-650 2850);
WIRE 16 -1 (-850 2800)(-850 2750);
WIRE 16 -1 (-850 2800)(-650 2800);
WIRE 16 -1 (-850 2750)(-650 2750);
WIRE 16 -1 (-5100 2050)(-5100 2150);
WIRE 16 -1 (-5100 2050)(-2950 2050);
WIRE 16 -1 (550 2950)(550 3125);
WIRE 16 -1 (550 2900)(550 2950);
WIRE 16 -1 (550 2950)(350 2950);
WIRE 16 -1 (550 2900)(350 2900);
WIRE 16 -1 (1100 1150)(1100 1250);
WIRE 16 -1 (1100 1250)(1100 1300);
WIRE 16 -1 (1100 1250)(1300 1250);
WIRE 16 -1 (1100 1300)(1100 1350);
WIRE 16 -1 (1100 1300)(1300 1300);
WIRE 16 -1 (1100 1350)(1100 1400);
WIRE 16 -1 (1100 1350)(1300 1350);
WIRE 16 -1 (1100 1400)(1100 1450);
WIRE 16 -1 (1100 1400)(1300 1400);
WIRE 16 -1 (1100 1450)(1100 1500);
WIRE 16 -1 (1100 1450)(1300 1450);
WIRE 16 -1 (1100 1500)(1100 1550);
WIRE 16 -1 (1100 1500)(1300 1500);
WIRE 16 -1 (1100 1550)(1100 1600);
WIRE 16 -1 (1100 1550)(1300 1550);
WIRE 16 -1 (1100 1600)(1100 1650);
WIRE 16 -1 (1100 1600)(1300 1600);
WIRE 16 -1 (1100 1650)(1100 1700);
WIRE 16 -1 (1100 1650)(1300 1650);
WIRE 16 -1 (1100 1700)(1100 1750);
WIRE 16 -1 (1100 1700)(1300 1700);
WIRE 16 -1 (1100 1750)(1100 1800);
WIRE 16 -1 (1100 1750)(1300 1750);
WIRE 16 -1 (1100 1800)(1100 1850);
WIRE 16 -1 (1100 1800)(1300 1800);
WIRE 16 -1 (1100 1850)(1100 1900);
WIRE 16 -1 (1100 1850)(1300 1850);
WIRE 16 -1 (1100 1900)(1100 1950);
WIRE 16 -1 (1100 1900)(1300 1900);
WIRE 16 -1 (1100 1950)(1100 2000);
WIRE 16 -1 (1100 1950)(1300 1950);
WIRE 16 -1 (1100 2000)(1100 2050);
WIRE 16 -1 (1100 2000)(1300 2000);
WIRE 16 -1 (1100 2050)(1100 2100);
WIRE 16 -1 (1100 2050)(1300 2050);
WIRE 16 -1 (1100 2100)(1100 2150);
WIRE 16 -1 (1100 2100)(1300 2100);
WIRE 16 -1 (1100 2150)(1100 2200);
WIRE 16 -1 (1100 2150)(1300 2150);
WIRE 16 -1 (1100 2200)(1100 2250);
WIRE 16 -1 (1100 2200)(1300 2200);
WIRE 16 -1 (1100 2250)(1100 2300);
WIRE 16 -1 (1100 2250)(1300 2250);
WIRE 16 -1 (1100 2300)(1100 2350);
WIRE 16 -1 (1100 2300)(1300 2300);
WIRE 16 -1 (1100 2350)(1100 2400);
WIRE 16 -1 (1100 2350)(1300 2350);
WIRE 16 -1 (1100 2400)(1100 2450);
WIRE 16 -1 (1100 2400)(1300 2400);
WIRE 16 -1 (1100 2450)(1100 2500);
WIRE 16 -1 (1100 2450)(1300 2450);
WIRE 16 -1 (1100 2500)(1100 2550);
WIRE 16 -1 (1100 2500)(1300 2500);
WIRE 16 -1 (1100 2550)(1100 2600);
WIRE 16 -1 (1100 2550)(1300 2550);
WIRE 16 -1 (1100 2600)(1100 2650);
WIRE 16 -1 (1100 2600)(1300 2600);
WIRE 16 -1 (1100 2650)(1100 2700);
WIRE 16 -1 (1100 2650)(1300 2650);
WIRE 16 -1 (1100 2700)(1100 2750);
WIRE 16 -1 (1100 2700)(1300 2700);
WIRE 16 -1 (1100 2750)(1100 2800);
WIRE 16 -1 (1100 2750)(1300 2750);
WIRE 16 -1 (1100 2800)(1100 2850);
WIRE 16 -1 (1100 2800)(1300 2800);
WIRE 16 -1 (1100 2850)(1100 2900);
WIRE 16 -1 (1100 2850)(1300 2850);
WIRE 16 -1 (1100 2900)(1100 2950);
WIRE 16 -1 (1100 2900)(1300 2900);
WIRE 16 -1 (1100 2950)(1100 3000);
WIRE 16 -1 (1100 2950)(1300 2950);
WIRE 16 -1 (1100 3000)(1100 3050);
WIRE 16 -1 (1100 3000)(1300 3000);
WIRE 16 -1 (1100 3050)(1100 3100);
WIRE 16 -1 (1100 3050)(1300 3050);
WIRE 16 -1 (1100 3100)(1100 3150);
WIRE 16 -1 (1100 3100)(1300 3100);
WIRE 16 -1 (1100 3150)(1100 3200);
WIRE 16 -1 (1100 3150)(1300 3150);
WIRE 16 -1 (1100 3200)(1100 3250);
WIRE 16 -1 (1100 3200)(1300 3200);
WIRE 16 -1 (1100 3250)(1100 3300);
WIRE 16 -1 (1100 3250)(1300 3250);
WIRE 16 -1 (1100 3300)(1100 3350);
WIRE 16 -1 (1100 3300)(1300 3300);
WIRE 16 -1 (1100 3350)(1100 3400);
WIRE 16 -1 (1100 3350)(1300 3350);
WIRE 16 -1 (1100 3400)(1100 3450);
WIRE 16 -1 (1100 3400)(1300 3400);
WIRE 16 -1 (1100 3450)(1100 3500);
WIRE 16 -1 (1100 3450)(1300 3450);
WIRE 16 -1 (1100 3500)(1100 3550);
WIRE 16 -1 (1100 3500)(1300 3500);
WIRE 16 -1 (1100 3550)(1300 3550);
WIRE 17 -1 (950 3475)(950 3575);
WIRE 17 -1 (950 3575)(950 3675);
WIRE 17 -1 (950 3675)(950 3775);
WIRE 17 -1 (950 3775)(950 3875);
WIRE 17 -1 (950 3875)(950 3975);
WIRE 17 -1 (950 3975)(950 4075);
WIRE 17 -1 (950 4075)(950 4175);
WIRE 17 -1 (950 4175)(950 4275);
WIRE 17 -1 (950 4275)(950 4375);
WIRE 17 -1 (950 4375)(950 4475);
WIRE 17 -1 (950 4475)(950 4575);
WIRE 17 -1 (950 4575)(950 4675);
WIRE 17 -1 (950 4675)(950 4775);
WIRE 17 -1 (950 4775)(950 4875);
WIRE 17 -1 (950 4875)(950 4975);
WIRE 17 -1 (1550 5200)(950 5200);
FORCEPROP 2 LAST SIG_NAME M_K_DQS_DN<17:0>
J 0
(1000 5210);
DISPLAY 0.617021 (1000 5210);
PAINT ORANGE (1000 5210);
WIRE 17 -1 (950 5175)(950 5200);
WIRE 17 -1 (950 4975)(950 5075);
WIRE 17 -1 (950 5075)(950 5175);
WIRE 17 -1 (750 3525)(750 3625);
WIRE 17 -1 (750 3625)(750 3725);
WIRE 17 -1 (750 3725)(750 3825);
WIRE 17 -1 (750 3825)(750 3925);
WIRE 17 -1 (750 3925)(750 4025);
WIRE 17 -1 (750 4025)(750 4125);
WIRE 17 -1 (750 4125)(750 4225);
WIRE 17 -1 (750 4225)(750 4325);
WIRE 17 -1 (750 4325)(750 4425);
WIRE 17 -1 (750 4425)(750 4525);
WIRE 17 -1 (750 4525)(750 4625);
WIRE 17 -1 (750 4625)(750 4725);
WIRE 17 -1 (750 4725)(750 4825);
WIRE 17 -1 (750 4825)(750 4925);
WIRE 17 -1 (750 4925)(750 5025);
WIRE 17 -1 (1550 5250)(750 5250);
FORCEPROP 2 LAST SIG_NAME M_K_DQS_DP<17:0>
J 0
(1000 5260);
DISPLAY 0.617021 (1000 5260);
PAINT ORANGE (1000 5260);
WIRE 17 -1 (750 5225)(750 5250);
WIRE 17 -1 (750 5025)(750 5125);
WIRE 17 -1 (750 5125)(750 5225);
WIRE 17 -1 (-1650 1725)(-1650 1775);
WIRE 17 -1 (-1650 1775)(-1650 1825);
WIRE 17 -1 (-1650 1825)(-1650 1875);
WIRE 17 -1 (-1650 1875)(-1650 1925);
WIRE 17 -1 (-1650 1925)(-1650 1975);
WIRE 17 -1 (-1650 1975)(-1650 2025);
WIRE 17 -1 (-1650 2025)(-1650 2075);
WIRE 17 -1 (-1650 2075)(-1650 2125);
WIRE 17 -1 (-1650 2125)(-1650 2175);
WIRE 17 -1 (-1650 2175)(-1650 2225);
WIRE 17 -1 (-1650 2225)(-1650 2275);
WIRE 17 -1 (-1650 2275)(-1650 2325);
WIRE 17 -1 (-1650 2325)(-1650 2375);
WIRE 17 -1 (-1650 2375)(-1650 2425);
WIRE 17 -1 (-1650 2425)(-1650 2475);
WIRE 17 -1 (-1650 2475)(-1650 2525);
WIRE 17 -1 (-1650 2525)(-1650 2575);
WIRE 17 -1 (-1650 2575)(-1650 2625);
WIRE 17 -1 (-1650 2625)(-1650 2675);
WIRE 17 -1 (-1650 2675)(-1650 2725);
WIRE 17 -1 (-1650 2725)(-1650 2775);
WIRE 17 -1 (-1650 2775)(-1650 2825);
WIRE 17 -1 (-1650 2825)(-1650 2875);
WIRE 17 -1 (-1650 2875)(-1650 2925);
WIRE 17 -1 (-1650 2925)(-1650 2975);
WIRE 17 -1 (-1650 2975)(-1650 3025);
WIRE 17 -1 (-1650 3025)(-1650 3075);
WIRE 17 -1 (-1650 3075)(-1650 3125);
WIRE 17 -1 (-1650 3125)(-1650 3175);
WIRE 17 -1 (-1650 3175)(-1650 3225);
WIRE 17 -1 (-1650 3225)(-1650 3275);
WIRE 17 -1 (-1650 3275)(-1650 3325);
WIRE 17 -1 (-1650 3325)(-1650 3375);
WIRE 17 -1 (-1650 3375)(-1650 3425);
WIRE 17 -1 (-1650 3425)(-1650 3475);
WIRE 17 -1 (-1650 3475)(-1650 3525);
WIRE 17 -1 (-1650 3525)(-1650 3575);
WIRE 17 -1 (-1650 3575)(-1650 3625);
WIRE 17 -1 (-1650 3625)(-1650 3675);
WIRE 17 -1 (-1650 3675)(-1650 3725);
WIRE 17 -1 (-1650 3725)(-1650 3775);
WIRE 17 -1 (-1650 3775)(-1650 3825);
WIRE 17 -1 (-1650 3825)(-1650 3875);
WIRE 17 -1 (-1650 3875)(-1650 3925);
WIRE 17 -1 (-1650 3925)(-1650 3975);
WIRE 17 -1 (-1650 3975)(-1650 4025);
WIRE 17 -1 (-1650 4025)(-1650 4075);
WIRE 17 -1 (-1650 4075)(-1650 4125);
WIRE 17 -1 (-1650 4125)(-1650 4175);
WIRE 17 -1 (-1650 4175)(-1650 4225);
WIRE 17 -1 (-1650 4225)(-1650 4275);
WIRE 17 -1 (-1650 4275)(-1650 4325);
WIRE 17 -1 (-1650 4325)(-1650 4375);
WIRE 17 -1 (-1650 4375)(-1650 4425);
WIRE 17 -1 (-1150 4900)(-1650 4900);
FORCEPROP 2 LAST SIG_NAME M_K_DQ<63:0>
J 0
(-1560 4910);
DISPLAY 0.617021 (-1560 4910);
PAINT ORANGE (-1560 4910);
WIRE 17 -1 (-1650 4425)(-1650 4475);
WIRE 17 -1 (-1650 4475)(-1650 4525);
WIRE 17 -1 (-1650 4875)(-1650 4900);
WIRE 17 -1 (-1650 4825)(-1650 4875);
WIRE 17 -1 (-1650 4525)(-1650 4575);
WIRE 17 -1 (-1650 4575)(-1650 4625);
WIRE 17 -1 (-1650 4775)(-1650 4825);
WIRE 17 -1 (-1650 4725)(-1650 4775);
WIRE 17 -1 (-1650 4625)(-1650 4675);
WIRE 17 -1 (-1650 4675)(-1650 4725);
WIRE 17 -1 (-3800 4900)(-3250 4900);
FORCEPROP 2 LAST SIG_NAME M_K_MA<17:0>
J 0
(-3775 4910);
DISPLAY 0.617021 (-3775 4910);
PAINT ORANGE (-3775 4910);
WIRE 17 -1 (-3250 4875)(-3250 4900);
WIRE 17 -1 (-3250 4825)(-3250 4875);
WIRE 17 -1 (-3250 4775)(-3250 4825);
WIRE 17 -1 (-3250 4725)(-3250 4775);
WIRE 17 -1 (-3250 4675)(-3250 4725);
WIRE 17 -1 (-3250 4625)(-3250 4675);
WIRE 17 -1 (-3250 4575)(-3250 4625);
WIRE 17 -1 (-3250 4525)(-3250 4575);
WIRE 17 -1 (-3250 4475)(-3250 4525);
WIRE 17 -1 (-3250 4425)(-3250 4475);
WIRE 17 -1 (-3250 4375)(-3250 4425);
WIRE 17 -1 (-3250 4325)(-3250 4375);
WIRE 17 -1 (-3250 4025)(-3250 4075);
WIRE 17 -1 (-3250 4075)(-3250 4125);
WIRE 17 -1 (-3250 4275)(-3250 4325);
WIRE 17 -1 (-3250 4225)(-3250 4275);
WIRE 17 -1 (-3250 4125)(-3250 4175);
WIRE 17 -1 (-3250 4175)(-3250 4225);
WIRE 17 -1 (-3600 3675)(-3600 3575);
WIRE 17 -1 (-3600 3750)(-4200 3750);
FORCEPROP 2 LAST SIG_NAME M_K_CLK_DP<3:0>
J 0
(-4150 3760);
DISPLAY 0.617021 (-4150 3760);
PAINT ORANGE (-4150 3760);
WIRE 17 -1 (-3600 3750)(-3600 3675);
WIRE 17 -1 (-3750 3700)(-4200 3700);
FORCEPROP 2 LAST SIG_NAME M_K_CLK_DN<3:0>
J 0
(-4150 3710);
DISPLAY 0.617021 (-4150 3710);
PAINT ORANGE (-4150 3710);
WIRE 17 -1 (-3750 3525)(-3750 3625);
WIRE 17 -1 (-3750 3625)(-3750 3700);
WIRE 17 -1 (-3250 3850)(-3800 3850);
FORCEPROP 2 LAST SIG_NAME M_K_BG<1:0>
J 0
(-3775 3860);
DISPLAY 0.617021 (-3775 3860);
PAINT ORANGE (-3775 3860);
WIRE 17 -1 (-3250 3850)(-3250 3825);
WIRE 17 -1 (-3250 3775)(-3250 3825);
WIRE 17 -1 (-3250 3875)(-3250 3925);
WIRE 17 -1 (-3250 3950)(-3800 3950);
FORCEPROP 2 LAST SIG_NAME M_K_BA<1:0>
J 0
(-3775 3960);
DISPLAY 0.617021 (-3775 3960);
PAINT ORANGE (-3775 3960);
WIRE 17 -1 (-3250 3950)(-3250 3925);
WIRE 17 -1 (-3250 3225)(-3250 3275);
WIRE 17 -1 (-3250 3400)(-3800 3400);
FORCEPROP 2 LAST SIG_NAME M_K_CS_N<7:0>
J 0
(-3775 3410);
DISPLAY 0.617021 (-3775 3410);
PAINT ORANGE (-3775 3410);
WIRE 17 -1 (-3250 3375)(-3250 3400);
WIRE 17 -1 (-3250 3275)(-3250 3325);
WIRE 17 -1 (-3250 3325)(-3250 3375);
WIRE 17 -1 (-3250 2475)(-3250 2525);
WIRE 17 -1 (-3250 2525)(-3250 2575);
WIRE 17 -1 (-3250 2850)(-3800 2850);
FORCEPROP 2 LAST SIG_NAME M_K_ECC<7:0>
J 0
(-3775 2860);
DISPLAY 0.617021 (-3775 2860);
PAINT ORANGE (-3775 2860);
WIRE 17 -1 (-3250 2575)(-3250 2625);
WIRE 17 -1 (-3250 2625)(-3250 2675);
WIRE 17 -1 (-3250 2825)(-3250 2850);
WIRE 17 -1 (-3250 2775)(-3250 2825);
WIRE 17 -1 (-3250 2675)(-3250 2725);
WIRE 17 -1 (-3250 2725)(-3250 2775);
WIRE 17 -1 (-3250 3150)(-3800 3150);
FORCEPROP 2 LAST SIG_NAME M_K_CKE<3:0>
J 0
(-3775 3160);
DISPLAY 0.617021 (-3775 3160);
PAINT ORANGE (-3775 3160);
WIRE 17 -1 (-3250 3075)(-3250 3125);
WIRE 17 -1 (-3250 3125)(-3250 3150);
WIRE 17 -1 (-3250 3000)(-3800 3000);
FORCEPROP 2 LAST SIG_NAME M_K_ODT<3:0>
J 0
(-3775 3010);
DISPLAY 0.617021 (-3775 3010);
PAINT ORANGE (-3775 3010);
WIRE 17 -1 (-3250 2975)(-3250 3000);
WIRE 17 -1 (-3250 2925)(-3250 2975);
WIRE 16 -1 (-2950 4700)(-3150 4700);
WIRE 16 -1 (-2950 4650)(-3150 4650);
WIRE 16 -1 (-2950 4600)(-3150 4600);
WIRE 16 -1 (-1750 4600)(-1950 4600);
WIRE 16 -1 (-1750 4350)(-1950 4350);
WIRE 16 -1 (850 3950)(450 3950);
WIRE 16 -1 (-2950 2200)(-3975 2200);
FORCEPROP 2 LAST SIG_NAME M_K_ALERT_N
J 0
(-3925 2210);
DISPLAY 0.617021 (-3925 2210);
PAINT ORANGE (-3925 2210);
WIRE 16 -1 (-4700 1700)(-4600 1700);
WIRE 16 -1 (-4600 1700)(-4600 1600);
WIRE 16 -1 (-2950 1700)(-4600 1700);
FORCEPROP 2 LAST SIG_NAME M_K_VREF
J 0
(-3700 1710);
DISPLAY 0.617021 (-3700 1710);
PAINT ORANGE (-3700 1710);
WIRE 16 -1 (-3800 1550)(-2950 1550);
FORCEPROP 2 LAST SIG_NAME TP_CH_K_DIMM_K0_RFU_1
J 0
(-3750 1560);
DISPLAY 0.617021 (-3750 1560);
PAINT ORANGE (-3750 1560);
FORCEPROP 2 LASTPROP $XRERR UNIQUE?
J 0
(-4040 1550);
DISPLAY 0.638298 (-4040 1550);
PAINT MONO (-4040 1550);
DISPLAY INVISIBLE (-4040 1550);
WIRE 16 -1 (-3800 1500)(-2950 1500);
FORCEPROP 2 LAST SIG_NAME TP_CH_K_DIMM_K0_RFU_0
J 0
(-3750 1510);
DISPLAY 0.617021 (-3750 1510);
PAINT ORANGE (-3750 1510);
FORCEPROP 2 LASTPROP $XRERR UNIQUE?
J 0
(-4040 1500);
DISPLAY 0.638298 (-4040 1500);
PAINT MONO (-4040 1500);
DISPLAY INVISIBLE (-4040 1500);
WIRE 16 -1 (-3800 1600)(-2950 1600);
FORCEPROP 2 LAST SIG_NAME TP_CH_K_DIMM_K0_RFU_2
J 0
(-3750 1610);
DISPLAY 0.617021 (-3750 1610);
PAINT ORANGE (-3750 1610);
FORCEPROP 2 LASTPROP $XRERR UNIQUE?
J 0
(-4040 1600);
DISPLAY 0.638298 (-4040 1600);
PAINT MONO (-4040 1600);
DISPLAY INVISIBLE (-4040 1600);
WIRE 16 -1 (-2950 1850)(-3750 1850);
WIRE 16 -1 (-3750 1800)(-2950 1800);
FORCEPROP 2 LAST SIG_NAME SMB_DDR_KLM_VPP_SCL
J 0
(-3710 1810);
DISPLAY 0.617021 (-3710 1810);
PAINT ORANGE (-3710 1810);
WIRE 16 -1 (-3800 1400)(-2950 1400);
FORCEPROP 2 LAST SIG_NAME FM_ADR_COMPLETE_KLM_N
J 0
(-3750 1410);
DISPLAY 0.617021 (-3750 1410);
PAINT ORANGE (-3750 1410);
WIRE 16 -1 (-3400 2550)(-4125 2550);
FORCEPROP 2 LAST SIG_NAME FM_DIMM_EVENT_COD_N
J 0
(-4103 2563);
DISPLAY 0.617021 (-4103 2563);
PAINT ORANGE (-4103 2563);
WIRE 16 -1 (-3400 2550)(-3400 2250);
WIRE 16 -1 (-3400 2250)(-2950 2250);
WIRE 16 -1 (-3350 2750)(-3800 2750);
FORCEPROP 2 LAST SIG_NAME M_KLM_RST_N
J 0
(-3775 2760);
DISPLAY 0.617021 (-3775 2760);
PAINT ORANGE (-3775 2760);
WIRE 16 -1 (-3350 2300)(-3350 2750);
WIRE 16 -1 (-2950 2300)(-3350 2300);
WIRE 16 -1 (-3300 2800)(-3800 2800);
FORCEPROP 2 LAST SIG_NAME M_K_PAR
J 0
(-3775 2810);
DISPLAY 0.617021 (-3775 2810);
PAINT ORANGE (-3775 2810);
WIRE 16 -1 (-3300 2350)(-3300 2800);
WIRE 16 -1 (-2950 2350)(-3300 2350);
WIRE 16 -1 (-3100 3450)(-3800 3450);
FORCEPROP 2 LAST SIG_NAME M_K_C<2>
J 0
(-3775 3460);
DISPLAY 0.617021 (-3775 3460);
PAINT ORANGE (-3775 3460);
WIRE 16 -1 (-3100 3450)(-3100 3400);
WIRE 16 -1 (-3100 3400)(-2950 3400);
WIRE 16 -1 (-2950 3200)(-3150 3200);
WIRE 16 -1 (-2950 3050)(-3150 3050);
WIRE 16 -1 (-2950 2950)(-3150 2950);
WIRE 16 -1 (-2950 2900)(-3150 2900);
WIRE 16 -1 (-2950 2800)(-3150 2800);
WIRE 16 -1 (-2950 3850)(-3150 3850);
WIRE 16 -1 (-2950 3800)(-3150 3800);
WIRE 16 -1 (-2950 3100)(-3150 3100);
WIRE 16 -1 (-2950 2450)(-3150 2450);
WIRE 16 -1 (-2950 2500)(-3150 2500);
WIRE 16 -1 (-2950 2550)(-3150 2550);
WIRE 16 -1 (-2950 2600)(-3150 2600);
WIRE 16 -1 (-2950 2650)(-3150 2650);
WIRE 16 -1 (-2950 2700)(-3150 2700);
WIRE 16 -1 (-2950 2750)(-3150 2750);
WIRE 16 -1 (-2950 4050)(-3150 4050);
WIRE 16 -1 (-2950 4000)(-3150 4000);
WIRE 16 -1 (-2950 3250)(-3150 3250);
WIRE 16 -1 (-2950 3300)(-3150 3300);
WIRE 16 -1 (-2950 3350)(-3150 3350);
WIRE 16 -1 (-2950 3900)(-3150 3900);
WIRE 16 -1 (-2950 3750)(-3150 3750);
WIRE 16 -1 (-2950 3500)(-3650 3500);
WIRE 16 -1 (-2950 3550)(-3500 3550);
WIRE 16 -1 (-2950 3600)(-3650 3600);
WIRE 16 -1 (-2950 3650)(-3500 3650);
WIRE 16 -1 (-2950 2150)(-3950 2150);
FORCEPROP 2 LAST SIG_NAME M_K_ACT_N
J 0
(-3900 2160);
DISPLAY 0.617021 (-3900 2160);
PAINT ORANGE (-3900 2160);
WIRE 16 -1 (-1750 1950)(-1950 1950);
WIRE 16 -1 (-1750 1900)(-1950 1900);
WIRE 16 -1 (-1750 1850)(-1950 1850);
WIRE 16 -1 (-1750 1800)(-1950 1800);
WIRE 16 -1 (-1750 1700)(-1950 1700);
WIRE 16 -1 (-1750 1750)(-1950 1750);
WIRE 16 -1 (-1750 2000)(-1950 2000);
WIRE 16 -1 (-1750 2550)(-1950 2550);
WIRE 16 -1 (-1750 2450)(-1950 2450);
WIRE 16 -1 (-1750 2050)(-1950 2050);
WIRE 16 -1 (-1750 2100)(-1950 2100);
WIRE 16 -1 (-1750 2150)(-1950 2150);
WIRE 16 -1 (-1750 2200)(-1950 2200);
WIRE 16 -1 (-1750 2250)(-1950 2250);
WIRE 16 -1 (-1750 2300)(-1950 2300);
WIRE 16 -1 (-1750 2350)(-1950 2350);
WIRE 16 -1 (-1750 2400)(-1950 2400);
WIRE 16 -1 (-1750 2500)(-1950 2500);
WIRE 16 -1 (-1750 3000)(-1950 3000);
WIRE 16 -1 (-1750 3050)(-1950 3050);
WIRE 16 -1 (-1750 2600)(-1950 2600);
WIRE 16 -1 (-1750 2650)(-1950 2650);
WIRE 16 -1 (-1750 2700)(-1950 2700);
WIRE 16 -1 (-1750 2750)(-1950 2750);
WIRE 16 -1 (-1750 2850)(-1950 2850);
WIRE 16 -1 (-1750 2900)(-1950 2900);
WIRE 16 -1 (-1750 2950)(-1950 2950);
WIRE 16 -1 (-1750 2800)(-1950 2800);
WIRE 16 -1 (-1750 3500)(-1950 3500);
WIRE 16 -1 (-1750 3450)(-1950 3450);
WIRE 16 -1 (-1750 3200)(-1950 3200);
WIRE 16 -1 (-1750 3250)(-1950 3250);
WIRE 16 -1 (-1750 3300)(-1950 3300);
WIRE 16 -1 (-1750 3350)(-1950 3350);
WIRE 16 -1 (-1750 3400)(-1950 3400);
WIRE 16 -1 (-1750 3550)(-1950 3550);
WIRE 16 -1 (-1750 3100)(-1950 3100);
WIRE 16 -1 (-1750 3150)(-1950 3150);
WIRE 16 -1 (-1750 4050)(-1950 4050);
WIRE 16 -1 (-1750 3600)(-1950 3600);
WIRE 16 -1 (-1750 3650)(-1950 3650);
WIRE 16 -1 (-1750 3700)(-1950 3700);
WIRE 16 -1 (-1750 3750)(-1950 3750);
WIRE 16 -1 (-1750 3800)(-1950 3800);
WIRE 16 -1 (-1750 3850)(-1950 3850);
WIRE 16 -1 (-1750 3900)(-1950 3900);
WIRE 16 -1 (-1750 3950)(-1950 3950);
WIRE 16 -1 (-1750 4000)(-1950 4000);
WIRE 16 -1 (-2950 4800)(-3150 4800);
WIRE 16 -1 (-2950 4750)(-3150 4750);
WIRE 16 -1 (-2950 4550)(-3150 4550);
WIRE 16 -1 (-2950 4500)(-3150 4500);
WIRE 16 -1 (-2950 4100)(-3150 4100);
WIRE 16 -1 (-2950 4450)(-3150 4450);
WIRE 16 -1 (-2950 4400)(-3150 4400);
WIRE 16 -1 (-2950 4350)(-3150 4350);
WIRE 16 -1 (-2950 4300)(-3150 4300);
WIRE 16 -1 (-2950 4250)(-3150 4250);
WIRE 16 -1 (-2950 4150)(-3150 4150);
WIRE 16 -1 (-2950 4850)(-3150 4850);
WIRE 16 -1 (-2950 4200)(-3150 4200);
WIRE 16 -1 (-1750 4100)(-1950 4100);
WIRE 16 -1 (-1750 4150)(-1950 4150);
WIRE 16 -1 (-1750 4300)(-1950 4300);
WIRE 16 -1 (-1750 4400)(-1950 4400);
WIRE 16 -1 (-1750 4550)(-1950 4550);
WIRE 16 -1 (-1750 4450)(-1950 4450);
WIRE 16 -1 (-1750 4500)(-1950 4500);
WIRE 16 -1 (-1750 4250)(-1950 4250);
WIRE 16 -1 (-1750 4200)(-1950 4200);
WIRE 16 -1 (-1750 4850)(-1950 4850);
WIRE 16 -1 (-1750 4800)(-1950 4800);
WIRE 16 -1 (-1750 4750)(-1950 4750);
WIRE 16 -1 (-1750 4650)(-1950 4650);
WIRE 16 -1 (-1750 4700)(-1950 4700);
WIRE 16 -1 (850 4050)(450 4050);
WIRE 16 -1 (650 4000)(450 4000);
WIRE 16 -1 (650 3900)(450 3900);
WIRE 16 -1 (850 3850)(450 3850);
WIRE 16 -1 (650 3800)(450 3800);
WIRE 16 -1 (850 3750)(450 3750);
WIRE 16 -1 (650 3700)(450 3700);
WIRE 16 -1 (850 3650)(450 3650);
WIRE 16 -1 (650 3600)(450 3600);
WIRE 16 -1 (850 3550)(450 3550);
WIRE 16 -1 (650 3500)(450 3500);
WIRE 16 -1 (850 3450)(450 3450);
WIRE 16 -1 (650 4400)(450 4400);
WIRE 16 -1 (850 4350)(450 4350);
WIRE 16 -1 (650 4300)(450 4300);
WIRE 16 -1 (850 4250)(450 4250);
WIRE 16 -1 (650 4200)(450 4200);
WIRE 16 -1 (850 4150)(450 4150);
WIRE 16 -1 (650 4100)(450 4100);
WIRE 16 -1 (650 5100)(450 5100);
WIRE 16 -1 (850 5050)(450 5050);
WIRE 16 -1 (650 5000)(450 5000);
WIRE 16 -1 (850 4950)(450 4950);
WIRE 16 -1 (650 4900)(450 4900);
WIRE 16 -1 (850 4850)(450 4850);
WIRE 16 -1 (650 4800)(450 4800);
WIRE 16 -1 (850 4750)(450 4750);
WIRE 16 -1 (650 4700)(450 4700);
WIRE 16 -1 (850 4650)(450 4650);
WIRE 16 -1 (650 4600)(450 4600);
WIRE 16 -1 (850 4550)(450 4550);
WIRE 16 -1 (650 4500)(450 4500);
WIRE 16 -1 (850 4450)(450 4450);
WIRE 16 -1 (650 5200)(450 5200);
WIRE 16 -1 (850 5150)(450 5150);
DOT 1 (2500 3300);
DOT 1 (-850 2450);
DOT 1 (1100 2600);
DOT 1 (1100 2700);
DOT 1 (1100 3100);
DOT 1 (1100 1550);
DOT 1 (-3150 1950);
DOT 1 (-3150 2000);
DOT 1 (-850 2800);
DOT 1 (-850 1300);
DOT 1 (-850 2100);
DOT 1 (-850 2150);
DOT 1 (-850 2200);
DOT 1 (-850 1350);
DOT 1 (-850 1500);
DOT 1 (-850 1450);
DOT 1 (-850 1400);
DOT 1 (-850 1600);
DOT 1 (-850 1550);
DOT 1 (-850 1650);
DOT 1 (-850 1700);
DOT 1 (-850 1750);
DOT 1 (-850 1850);
DOT 1 (-850 1800);
DOT 1 (-850 1900);
DOT 1 (-850 2000);
DOT 1 (-850 1950);
DOT 1 (-850 2050);
DOT 1 (-850 2250);
DOT 1 (-850 2300);
DOT 1 (-850 2350);
DOT 1 (-850 2400);
DOT 1 (-850 2500);
DOT 1 (-850 2850);
DOT 1 (1100 1250);
DOT 1 (1100 1300);
DOT 1 (1100 1400);
DOT 1 (1100 1350);
DOT 1 (1100 1500);
DOT 1 (1100 1450);
DOT 1 (1100 1650);
DOT 1 (1100 1600);
DOT 1 (1100 1750);
DOT 1 (1100 1700);
DOT 1 (1100 1800);
DOT 1 (1100 1900);
DOT 1 (1100 1850);
DOT 1 (1100 2000);
DOT 1 (1100 2150);
DOT 1 (1100 2100);
DOT 1 (1100 2200);
DOT 1 (1100 2250);
DOT 1 (1100 2300);
DOT 1 (1100 2400);
DOT 1 (1100 2350);
DOT 1 (1100 2450);
DOT 1 (1100 2500);
DOT 1 (1100 2650);
DOT 1 (1100 2750);
DOT 1 (1100 2900);
DOT 1 (1100 2850);
DOT 1 (1100 2950);
DOT 1 (1100 3000);
DOT 1 (1100 3200);
DOT 1 (1100 3150);
DOT 1 (1100 3250);
DOT 1 (1100 3300);
DOT 1 (1100 3350);
DOT 1 (1100 3450);
DOT 1 (1100 3400);
DOT 1 (1100 3500);
DOT 1 (2500 3500);
DOT 1 (2500 3350);
DOT 1 (2500 3450);
DOT 1 (2500 3400);
DOT 1 (2500 3250);
DOT 1 (2500 3200);
DOT 1 (2500 3100);
DOT 1 (2500 3150);
DOT 1 (2500 3000);
DOT 1 (2500 3050);
DOT 1 (2500 2850);
DOT 1 (2500 2900);
DOT 1 (2500 2750);
DOT 1 (2500 2800);
DOT 1 (2500 2700);
DOT 1 (2500 2600);
DOT 1 (2500 2650);
DOT 1 (2500 2450);
DOT 1 (2500 2550);
DOT 1 (2500 2500);
DOT 1 (2500 2350);
DOT 1 (2500 2400);
DOT 1 (2500 2200);
DOT 1 (2500 2250);
DOT 1 (2500 2300);
DOT 1 (2500 2100);
DOT 1 (2500 2150);
DOT 1 (2500 2050);
DOT 1 (2500 2000);
DOT 1 (2500 1950);
DOT 1 (2500 1850);
DOT 1 (2500 1900);
DOT 1 (2500 1800);
DOT 1 (2500 1750);
DOT 1 (2500 1700);
DOT 1 (2500 1650);
DOT 1 (2500 1600);
DOT 1 (2500 1550);
DOT 1 (2500 1500);
DOT 1 (2500 1450);
DOT 1 (2500 1300);
DOT 1 (2500 1400);
DOT 1 (2500 1350);
DOT 1 (2500 1250);
DOT 1 (-4600 1700);
DOT 1 (1100 3050);
DOT 1 (550 2950);
DOT 1 (-850 2650);
DOT 1 (-850 2950);
DOT 1 (1100 2800);
DOT 1 (1100 2550);
DOT 1 (1100 2050);
DOT 1 (1100 1950);
DOT 1 (-850 2900);
DOT 1 (2500 2950);
FORCENOTE
PVDDQ (SINGLE SIDE) CAP: 10UF X1, 22UF X50
(-3950 5225) 0;
DISPLAY LEFT (-3950 5225);
DISPLAY 1.021277 (-3950 5225);
PAINT PURPLE (-3950 5225);
FORCENOTE
PVDDQ (DOUBLE SIDE) CAP: 100UF X8, 47UF X41
(-3950 5175) 0;
DISPLAY LEFT (-3950 5175);
DISPLAY 1.021277 (-3950 5175);
PAINT PURPLE (-3950 5175);
FORCENOTE
PVTT CAP: 100UF X2, 47UF X1
(-3950 5275) 0;
DISPLAY LEFT (-3950 5275);
DISPLAY 1.021277 (-3950 5275);
PAINT PURPLE (-3950 5275);
FORCENOTE
PVPP CAP: 10UF X12
(-3950 5325) 0;
DISPLAY LEFT (-3950 5325);
DISPLAY 1.021277 (-3950 5325);
PAINT PURPLE (-3950 5325);
FORCENOTE
CAP BETWEEN DIMM
(-3950 5400) 0;
DISPLAY LEFT (-3950 5400);
DISPLAY 1.276596 (-3950 5400);
PAINT PURPLE (-3950 5400);
FORCENOTE
SMBUS ADDR: 0XA0
(-5275 1009) 0;
DISPLAY LEFT (-5275 1009);
DISPLAY 1.957447 (-5275 1009);
PAINT PURPLE (-5275 1009);
FORCENOTE
PLACE CAP NEAR DIMM CONNECTOR
(-5288 1152) 0;
DISPLAY LEFT (-5288 1152);
DISPLAY 1.595745 (-5288 1152);
PAINT PURPLE (-5288 1152);
QUIT
